FILE_TYPE = MACRO_DRAWING;
SET COLOR_WIRE YELLOW;
SET COLOR_PROP ORANGE;
SET COLOR_DOT WHITE;
SET COLOR_ARC YELLOW;
SET COLOR_BODY GREEN;
SET COLOR_NOTE PURPLE;
SET PROP_DISPLAY VALUE;
SET PAGE_NUMBER P159;
FORCEADD UNIVERSAL_GND..1
(-1550 -2800);
FORCEPROP 3 LASTPIN (-1550 -2750) SIG_NAME GND\g
J 0
(-1540 -2740);
DISPLAY 0.659574 (-1540 -2740);
PAINT MONO (-1540 -2740);
DISPLAY INVISIBLE (-1540 -2740);
FORCEPROP 2 LAST CDS_LIB logical_power
J 0
(-1550 -2800);
DISPLAY INVISIBLE (-1550 -2800);
FORCEPROP 1 LAST HDL_POWER GND
J 1
(-1525 -2875);
DISPLAY 0.872340 (-1525 -2875);
PAINT GREEN (-1525 -2875);
DISPLAY INVISIBLE (-1525 -2875);
FORCEPROP 2 LAST ROOM IO_SLOT
J 1
(-1775 -2725);
DISPLAY 0.744681 (-1775 -2725);
DISPLAY INVISIBLE (-1775 -2725);
FORCEPROP 1 LAST PATH I1
J 0
(-1475 -2800);
DISPLAY 0.872340 (-1475 -2800);
PAINT AQUA (-1475 -2800);
DISPLAY INVISIBLE (-1475 -2800);
FORCEADD Q_RES..2
(-1550 -1000);
FORCEPROP 1 LAST PART_NUMBER CS21002FB06
J 0
(-1510 -1125);
DISPLAY 0.638298 (-1510 -1125);
DISPLAY INVISIBLE (-1510 -1125);
FORCEPROP 2 LAST ROOM PCIE REDRIVER1_BOM2
J 0
(-1500 -825);
DISPLAY 0.638298 (-1500 -825);
FORCEPROP 1 LAST MATERIAL CHIP
J 0
(-1510 -1075);
DISPLAY 0.638298 (-1510 -1075);
FORCEPROP 1 LAST VALUE 1K
J 0
(-1505 -925);
DISPLAY 0.638298 (-1505 -925);
FORCEPROP 1 LAST WATTAGE 1/16W
J 0
(-1510 -1025);
DISPLAY 0.638298 (-1510 -1025);
FORCEPROP 1 LAST TOLERANCE 1%
J 0
(-1505 -975);
DISPLAY 0.638298 (-1505 -975);
FORCEPROP 1 LAST PACK_TYPE 0402LF
J 0
(-1510 -1175);
DISPLAY 0.638298 (-1510 -1175);
FORCEPROP 1 LAST $LOCATION R4694
J 0
(-1505 -875);
DISPLAY 0.978723 (-1505 -875);
FORCEPROP 1 LASTPIN (-1550 -900) $PN 1
J 0
(-1545 -938);
DISPLAY 0.787234 (-1545 -938);
PAINT MONO (-1545 -938);
FORCEPROP 1 LASTPIN (-1550 -1100) $PN 2
J 0
(-1545 -1090);
DISPLAY 0.787234 (-1545 -1090);
PAINT MONO (-1545 -1090);
FORCEPROP 2 LAST CDS_LIB pure_quanta
J 0
(-1550 -1000);
DISPLAY INVISIBLE (-1550 -1000);
FORCEPROP 1 LAST PATH I10
J 0
(-1500 -825);
DISPLAY 0.978723 (-1500 -825);
PAINT WHITE (-1500 -825);
DISPLAY INVISIBLE (-1500 -825);
FORCEPROP 0 LAST CDS_LOCATION R4694
J 0
(-1500 -825);
DISPLAY 1.021277 (-1500 -825);
DISPLAY INVISIBLE (-1500 -825);
FORCEPROP 0 LAST $SEC 1
J 0
(-1500 -825);
DISPLAY 0.680851 (-1500 -825);
PAINT MONO (-1500 -825);
DISPLAY INVISIBLE (-1500 -825);
FORCEPROP 0 LAST CDS_SEC 1
J 0
(-1500 -825);
DISPLAY 1.021277 (-1500 -825);
DISPLAY INVISIBLE (-1500 -825);
FORCEADD Q_CAP..1
(850 2175);
FORCEPROP 1 LAST PART_NUMBER CH4104K1B00
J 0
(900 2025);
DISPLAY 0.808511 (900 2025);
DISPLAY INVISIBLE (900 2025);
FORCEPROP 1 LAST PACK_TYPE 0402
J 0
(900 2025);
DISPLAY 0.638298 (900 2025);
FORCEPROP 1 LAST VALUE 0.1UF
J 0
(900 2225);
DISPLAY 0.638298 (900 2225);
FORCEPROP 1 LAST VOLTAGE 25V
J 0
(900 2175);
DISPLAY 0.638298 (900 2175);
FORCEPROP 1 LAST MATERIAL X7R
J 0
(900 2075);
DISPLAY 0.638298 (900 2075);
FORCEPROP 1 LAST TOLERANCE 10%
J 0
(900 2125);
DISPLAY 0.638298 (900 2125);
FORCEPROP 2 LAST ROOM PCIE REDRIVER1_BOM2
J 0
(875 2350);
DISPLAY 0.510638 (875 2350);
FORCEPROP 1 LAST $LOCATION C2358
J 0
(900 2275);
DISPLAY 0.787234 (900 2275);
FORCEPROP 1 LASTPIN (850 2275) $PN 1
J 0
(860 2255);
DISPLAY 0.787234 (860 2255);
PAINT MONO (860 2255);
FORCEPROP 1 LASTPIN (850 2075) $PN 2
J 0
(860 2055);
DISPLAY 0.787234 (860 2055);
PAINT MONO (860 2055);
FORCEPROP 2 LAST CDS_LIB pure_quanta
J 0
(850 2175);
DISPLAY INVISIBLE (850 2175);
FORCEPROP 1 LAST PATH I100
J 0
(900 2325);
DISPLAY 0.978723 (900 2325);
PAINT WHITE (900 2325);
DISPLAY INVISIBLE (900 2325);
FORCEPROP 0 LAST CDS_LOCATION C2358
J 0
(900 2325);
DISPLAY 1.021277 (900 2325);
DISPLAY INVISIBLE (900 2325);
FORCEPROP 0 LAST $SEC 1
J 0
(900 2325);
DISPLAY 0.680851 (900 2325);
PAINT MONO (900 2325);
DISPLAY INVISIBLE (900 2325);
FORCEPROP 0 LAST CDS_SEC 1
J 0
(900 2325);
DISPLAY 1.021277 (900 2325);
DISPLAY INVISIBLE (900 2325);
FORCEADD UNIVERSAL_GND..1
(2375 775);
FORCEPROP 3 LASTPIN (2375 825) SIG_NAME GND\g
J 0
(2385 835);
DISPLAY 0.659574 (2385 835);
PAINT MONO (2385 835);
DISPLAY INVISIBLE (2385 835);
FORCEPROP 1 LAST HDL_POWER GND
J 1
(2400 700);
DISPLAY 0.872340 (2400 700);
PAINT GREEN (2400 700);
DISPLAY INVISIBLE (2400 700);
FORCEPROP 2 LAST CDS_LIB logical_power
J 0
(2375 775);
DISPLAY INVISIBLE (2375 775);
FORCEPROP 1 LAST PATH I101
J 0
(2450 775);
DISPLAY 0.872340 (2450 775);
PAINT AQUA (2450 775);
DISPLAY INVISIBLE (2450 775);
FORCEADD Q_RES..1
(2825 1450);
FORCEPROP 1 LAST PART_NUMBER CS00002JB13
J 0
(2550 1325);
DISPLAY 0.723404 (2550 1325);
PAINT WHITE (2550 1325);
DISPLAY INVISIBLE (2550 1325);
FORCEPROP 2 LAST ROOM PCIE REDRIVER1_BOM2
J 0
(2475 1375);
DISPLAY 0.638298 (2475 1375);
FORCEPROP 1 LAST PACK_TYPE 0402LF
J 0
(3125 1450);
DISPLAY 0.574468 (3125 1450);
FORCEPROP 1 LAST MATERIAL CHIP
J 0
(3000 1450);
DISPLAY 0.574468 (3000 1450);
FORCEPROP 1 LAST VALUE 0
J 2
(2975 1450);
DISPLAY 0.574468 (2975 1450);
FORCEPROP 1 LAST $LOCATION R4651
J 0
(2775 1500);
DISPLAY 0.638298 (2775 1500);
FORCEPROP 1 LASTPIN (2725 1450) $PN 1
J 0
(2737 1462);
DISPLAY 0.787234 (2737 1462);
PAINT MONO (2737 1462);
FORCEPROP 1 LASTPIN (2925 1450) $PN 2
J 0
(2887 1462);
DISPLAY 0.787234 (2887 1462);
PAINT MONO (2887 1462);
FORCEPROP 1 LAST WATTAGE 1/16W
J 2
(2900 1375);
DISPLAY 0.723404 (2900 1375);
PAINT SKYBLUE (2900 1375);
DISPLAY INVISIBLE (2900 1375);
FORCEPROP 1 LAST TOLERANCE 5%
J 0
(2625 1375);
DISPLAY 0.723404 (2625 1375);
PAINT SKYBLUE (2625 1375);
DISPLAY INVISIBLE (2625 1375);
FORCEPROP 2 LAST CDS_LIB pure_quanta
J 0
(2825 1450);
DISPLAY INVISIBLE (2825 1450);
FORCEPROP 1 LAST PATH I102
J 0
(2775 1600);
DISPLAY 0.978723 (2775 1600);
PAINT WHITE (2775 1600);
DISPLAY INVISIBLE (2775 1600);
FORCEPROP 0 LAST CDS_LOCATION R4651
J 0
(2775 1550);
DISPLAY 1.021277 (2775 1550);
DISPLAY INVISIBLE (2775 1550);
FORCEPROP 0 LAST $SEC 1
J 0
(2775 1550);
DISPLAY 0.680851 (2775 1550);
PAINT MONO (2775 1550);
DISPLAY INVISIBLE (2775 1550);
FORCEPROP 0 LAST CDS_SEC 1
J 0
(2775 1550);
DISPLAY 1.021277 (2775 1550);
DISPLAY INVISIBLE (2775 1550);
FORCEADD OFFPAGE..2
(3250 1150);
FORCEPROP 2 LAST $XR0 167 
J 0
(3439 1150);
DISPLAY 0.638298 (3439 1150);
PAINT MONO (3439 1150);
FORCEPROP 2 LAST CDS_LIB standard
J 0
(3250 1150);
DISPLAY INVISIBLE (3250 1150);
FORCEPROP 1 LAST COMMENT_BODY TRUE
J 0
(3205 1055);
DISPLAY 0.872340 (3205 1055);
PAINT GREEN (3205 1055);
DISPLAY INVISIBLE (3205 1055);
FORCEPROP 1 LAST OFFPAGE TRUE
J 0
(3575 1025);
DISPLAY 0.872340 (3575 1025);
PAINT GREEN (3575 1025);
DISPLAY INVISIBLE (3575 1025);
FORCEPROP 2 LAST PATH I103
J 0
(3450 1200);
DISPLAY 1.021277 (3450 1200);
DISPLAY INVISIBLE (3450 1200);
FORCEADD OFFPAGE..2
(3250 1200);
FORCEPROP 2 LAST $XR0 167 
J 0
(3439 1200);
DISPLAY 0.638298 (3439 1200);
PAINT MONO (3439 1200);
FORCEPROP 2 LAST CDS_LIB standard
J 0
(3250 1200);
DISPLAY INVISIBLE (3250 1200);
FORCEPROP 1 LAST COMMENT_BODY TRUE
J 0
(3205 1105);
DISPLAY 0.872340 (3205 1105);
PAINT GREEN (3205 1105);
DISPLAY INVISIBLE (3205 1105);
FORCEPROP 1 LAST OFFPAGE TRUE
J 0
(3575 1075);
DISPLAY 0.872340 (3575 1075);
PAINT GREEN (3575 1075);
DISPLAY INVISIBLE (3575 1075);
FORCEPROP 2 LAST PATH I104
J 0
(3450 1250);
DISPLAY 1.021277 (3450 1250);
DISPLAY INVISIBLE (3450 1250);
FORCEADD OFFPAGE..2
(3250 1000);
FORCEPROP 2 LAST $XR0 167 
J 0
(3439 1000);
DISPLAY 0.638298 (3439 1000);
PAINT MONO (3439 1000);
FORCEPROP 2 LAST CDS_LIB standard
J 0
(3250 1000);
DISPLAY INVISIBLE (3250 1000);
FORCEPROP 1 LAST COMMENT_BODY TRUE
J 0
(3205 905);
DISPLAY 0.872340 (3205 905);
PAINT GREEN (3205 905);
DISPLAY INVISIBLE (3205 905);
FORCEPROP 1 LAST OFFPAGE TRUE
J 0
(3575 875);
DISPLAY 0.872340 (3575 875);
PAINT GREEN (3575 875);
DISPLAY INVISIBLE (3575 875);
FORCEPROP 2 LAST PATH I105
J 0
(3450 1050);
DISPLAY 1.021277 (3450 1050);
DISPLAY INVISIBLE (3450 1050);
FORCEADD OFFPAGE..2
(3250 1050);
FORCEPROP 2 LAST $XR0 167 
J 0
(3439 1050);
DISPLAY 0.638298 (3439 1050);
PAINT MONO (3439 1050);
FORCEPROP 2 LAST CDS_LIB standard
J 0
(3250 1050);
DISPLAY INVISIBLE (3250 1050);
FORCEPROP 1 LAST COMMENT_BODY TRUE
J 0
(3205 955);
DISPLAY 0.872340 (3205 955);
PAINT GREEN (3205 955);
DISPLAY INVISIBLE (3205 955);
FORCEPROP 1 LAST OFFPAGE TRUE
J 0
(3575 925);
DISPLAY 0.872340 (3575 925);
PAINT GREEN (3575 925);
DISPLAY INVISIBLE (3575 925);
FORCEPROP 2 LAST PATH I106
J 0
(3450 1100);
DISPLAY 1.021277 (3450 1100);
DISPLAY INVISIBLE (3450 1100);
FORCEADD OFFPAGE..4
(3175 1600);
FORCEPROP 2 LAST $XR0 167 
J 0
(3361 1600);
DISPLAY 0.638298 (3361 1600);
PAINT MONO (3361 1600);
FORCEPROP 1 LAST OFFPAGE TRUE
J 0
(3500 1475);
DISPLAY 0.872340 (3500 1475);
PAINT GREEN (3500 1475);
DISPLAY INVISIBLE (3500 1475);
FORCEPROP 1 LAST COMMENT_BODY TRUE
J 0
(3150 1500);
DISPLAY 0.872340 (3150 1500);
PAINT GREEN (3150 1500);
DISPLAY INVISIBLE (3150 1500);
FORCEPROP 2 LAST CDS_LIB standard
J 0
(3175 1600);
DISPLAY INVISIBLE (3175 1600);
FORCEPROP 2 LAST PATH I107
J 0
(3375 1650);
DISPLAY 1.021277 (3375 1650);
DISPLAY INVISIBLE (3375 1650);
FORCEADD OFFPAGE..4
(3175 1900);
FORCEPROP 2 LAST $XR0 167 
J 0
(3361 1900);
DISPLAY 0.638298 (3361 1900);
PAINT MONO (3361 1900);
FORCEPROP 1 LAST OFFPAGE TRUE
J 0
(3500 1775);
DISPLAY 0.872340 (3500 1775);
PAINT GREEN (3500 1775);
DISPLAY INVISIBLE (3500 1775);
FORCEPROP 1 LAST COMMENT_BODY TRUE
J 0
(3150 1800);
DISPLAY 0.872340 (3150 1800);
PAINT GREEN (3150 1800);
DISPLAY INVISIBLE (3150 1800);
FORCEPROP 2 LAST CDS_LIB standard
J 0
(3175 1900);
DISPLAY INVISIBLE (3175 1900);
FORCEPROP 2 LAST PATH I108
J 0
(3375 1950);
DISPLAY 1.021277 (3375 1950);
DISPLAY INVISIBLE (3375 1950);
FORCEADD OFFPAGE..4
(3175 2200);
FORCEPROP 2 LAST $XR0 167 
J 0
(3361 2200);
DISPLAY 0.638298 (3361 2200);
PAINT MONO (3361 2200);
FORCEPROP 1 LAST OFFPAGE TRUE
J 0
(3500 2075);
DISPLAY 0.872340 (3500 2075);
PAINT GREEN (3500 2075);
DISPLAY INVISIBLE (3500 2075);
FORCEPROP 1 LAST COMMENT_BODY TRUE
J 0
(3150 2100);
DISPLAY 0.872340 (3150 2100);
PAINT GREEN (3150 2100);
DISPLAY INVISIBLE (3150 2100);
FORCEPROP 2 LAST CDS_LIB standard
J 0
(3175 2200);
DISPLAY INVISIBLE (3175 2200);
FORCEPROP 2 LAST PATH I109
J 0
(3375 2250);
DISPLAY 1.021277 (3375 2250);
DISPLAY INVISIBLE (3375 2250);
FORCEADD Q_RES..2
(-1550 -450);
FORCEPROP 1 LAST PART_NUMBER CS21002FB06
J 0
(-1510 -575);
DISPLAY 0.638298 (-1510 -575);
DISPLAY INVISIBLE (-1510 -575);
FORCEPROP 1 LAST PACK_TYPE 0402LF
J 0
(-1510 -625);
DISPLAY 0.638298 (-1510 -625);
FORCEPROP 1 LAST MATERIAL EMPTY
J 0
(-1510 -525);
DISPLAY 0.638298 (-1510 -525);
PAINT RED (-1510 -525);
FORCEPROP 1 LAST TOLERANCE 1%
J 0
(-1505 -425);
DISPLAY 0.638298 (-1505 -425);
FORCEPROP 1 LAST WATTAGE 1/16W
J 0
(-1510 -475);
DISPLAY 0.638298 (-1510 -475);
FORCEPROP 1 LAST VALUE 1K
J 0
(-1505 -375);
DISPLAY 0.638298 (-1505 -375);
FORCEPROP 1 LAST $LOCATION R4644
J 0
(-1505 -325);
DISPLAY 0.638298 (-1505 -325);
FORCEPROP 1 LASTPIN (-1550 -350) $PN 1
J 0
(-1545 -388);
DISPLAY 0.787234 (-1545 -388);
PAINT MONO (-1545 -388);
FORCEPROP 1 LASTPIN (-1550 -550) $PN 2
J 0
(-1545 -540);
DISPLAY 0.787234 (-1545 -540);
PAINT MONO (-1545 -540);
FORCEPROP 2 LAST CDS_LIB pure_quanta
J 0
(-1550 -450);
DISPLAY INVISIBLE (-1550 -450);
FORCEPROP 1 LAST PATH I11
J 0
(-1500 -275);
DISPLAY 0.978723 (-1500 -275);
PAINT WHITE (-1500 -275);
DISPLAY INVISIBLE (-1500 -275);
FORCEPROP 0 LAST CDS_LOCATION R4644
J 0
(-1500 -275);
DISPLAY 1.021277 (-1500 -275);
DISPLAY INVISIBLE (-1500 -275);
FORCEPROP 0 LAST $SEC 1
J 0
(-1500 -275);
DISPLAY 0.680851 (-1500 -275);
PAINT MONO (-1500 -275);
DISPLAY INVISIBLE (-1500 -275);
FORCEPROP 0 LAST CDS_SEC 1
J 0
(-1500 -275);
DISPLAY 1.021277 (-1500 -275);
DISPLAY INVISIBLE (-1500 -275);
FORCEADD OFFPAGE..4
(4150 1450);
FORCEPROP 2 LAST $XR1 212 
J 0
(4456 1450);
DISPLAY 0.638298 (4456 1450);
PAINT MONO (4456 1450);
FORCEPROP 2 LAST $XR0 166 
J 0
(4336 1450);
DISPLAY 0.638298 (4336 1450);
PAINT MONO (4336 1450);
FORCEPROP 2 LAST CDS_LIB standard
J 0
(4150 1450);
DISPLAY INVISIBLE (4150 1450);
FORCEPROP 1 LAST OFFPAGE TRUE
J 0
(4475 1325);
DISPLAY 0.872340 (4475 1325);
PAINT GREEN (4475 1325);
DISPLAY INVISIBLE (4475 1325);
FORCEPROP 1 LAST COMMENT_BODY TRUE
J 0
(4125 1350);
DISPLAY 0.872340 (4125 1350);
PAINT GREEN (4125 1350);
DISPLAY INVISIBLE (4125 1350);
FORCEPROP 2 LAST PATH I110
J 0
(4475 1500);
DISPLAY 1.021277 (4475 1500);
DISPLAY INVISIBLE (4475 1500);
FORCEADD OFFPAGE..2
(-1450 1875);
FORCEPROP 2 LAST $XR0 167 
J 0
(-1261 1875);
DISPLAY 0.638298 (-1261 1875);
PAINT MONO (-1261 1875);
FORCEPROP 1 LAST COMMENT_BODY TRUE
J 0
(-1495 1780);
DISPLAY 0.872340 (-1495 1780);
PAINT GREEN (-1495 1780);
DISPLAY INVISIBLE (-1495 1780);
FORCEPROP 1 LAST OFFPAGE TRUE
J 0
(-1125 1750);
DISPLAY 0.872340 (-1125 1750);
PAINT AQUA (-1125 1750);
DISPLAY INVISIBLE (-1125 1750);
FORCEPROP 2 LAST CDS_LIB standard
J 0
(-1450 1875);
DISPLAY INVISIBLE (-1450 1875);
FORCEPROP 2 LAST PATH I111
J 0
(-1250 1925);
DISPLAY 1.021277 (-1250 1925);
DISPLAY INVISIBLE (-1250 1925);
FORCEADD UNIVERSAL_POWER..1
(-1550 -150);
FORCEPROP 3 LASTPIN (-1550 -200) SIG_NAME P3V3_AUX\g
J 0
(-1540 -190);
DISPLAY 0.659574 (-1540 -190);
PAINT MONO (-1540 -190);
DISPLAY INVISIBLE (-1540 -190);
FORCEPROP 1 LAST HDL_POWER P3V3_AUX
J 1
(-1550 -100);
DISPLAY 0.872340 (-1550 -100);
PAINT GREEN (-1550 -100);
FORCEPROP 2 LAST CDS_LIB logical_power
J 0
(-1550 -150);
DISPLAY INVISIBLE (-1550 -150);
FORCEPROP 1 LAST PATH I12
J 0
(-1500 -125);
DISPLAY 0.872340 (-1500 -125);
PAINT AQUA (-1500 -125);
DISPLAY INVISIBLE (-1500 -125);
FORCEADD Q_RES..2
(-1125 -1925);
FORCEPROP 1 LAST PART_NUMBER CS21002FB06
J 0
(-1085 -2050);
DISPLAY 0.638298 (-1085 -2050);
DISPLAY INVISIBLE (-1085 -2050);
FORCEPROP 1 LAST TOLERANCE 1%
J 0
(-1080 -1900);
DISPLAY 0.638298 (-1080 -1900);
FORCEPROP 1 LAST VALUE 1K
J 0
(-1080 -1850);
DISPLAY 0.638298 (-1080 -1850);
FORCEPROP 1 LAST PACK_TYPE 0402LF
J 0
(-1085 -2100);
DISPLAY 0.638298 (-1085 -2100);
FORCEPROP 1 LAST MATERIAL EMPTY
J 0
(-1085 -2000);
DISPLAY 0.638298 (-1085 -2000);
PAINT RED (-1085 -2000);
FORCEPROP 1 LAST WATTAGE 1/16W
J 0
(-1085 -1950);
DISPLAY 0.638298 (-1085 -1950);
FORCEPROP 1 LAST $LOCATION R4643
J 0
(-1080 -1800);
DISPLAY 0.978723 (-1080 -1800);
FORCEPROP 1 LASTPIN (-1125 -1825) $PN 1
J 0
(-1120 -1863);
DISPLAY 0.787234 (-1120 -1863);
PAINT MONO (-1120 -1863);
FORCEPROP 1 LASTPIN (-1125 -2025) $PN 2
J 0
(-1120 -2015);
DISPLAY 0.787234 (-1120 -2015);
PAINT MONO (-1120 -2015);
FORCEPROP 2 LAST CDS_LIB pure_quanta
J 0
(-1125 -1925);
DISPLAY INVISIBLE (-1125 -1925);
FORCEPROP 1 LAST PATH I13
J 0
(-1075 -1750);
DISPLAY 0.978723 (-1075 -1750);
PAINT WHITE (-1075 -1750);
DISPLAY INVISIBLE (-1075 -1750);
FORCEPROP 0 LAST CDS_LOCATION R4643
J 0
(-1075 -1750);
DISPLAY 1.021277 (-1075 -1750);
DISPLAY INVISIBLE (-1075 -1750);
FORCEPROP 0 LAST $SEC 1
J 0
(-1075 -1750);
DISPLAY 0.680851 (-1075 -1750);
PAINT MONO (-1075 -1750);
DISPLAY INVISIBLE (-1075 -1750);
FORCEPROP 0 LAST CDS_SEC 1
J 0
(-1075 -1750);
DISPLAY 1.021277 (-1075 -1750);
DISPLAY INVISIBLE (-1075 -1750);
FORCEADD UNIVERSAL_GND..1
(-1125 -1325);
FORCEPROP 3 LASTPIN (-1125 -1275) SIG_NAME GND\g
J 0
(-1115 -1265);
DISPLAY 0.659574 (-1115 -1265);
PAINT MONO (-1115 -1265);
DISPLAY INVISIBLE (-1115 -1265);
FORCEPROP 2 LAST CDS_LIB logical_power
J 0
(-1125 -1325);
DISPLAY INVISIBLE (-1125 -1325);
FORCEPROP 1 LAST HDL_POWER GND
J 1
(-1100 -1400);
DISPLAY 0.872340 (-1100 -1400);
PAINT GREEN (-1100 -1400);
DISPLAY INVISIBLE (-1100 -1400);
FORCEPROP 2 LAST ROOM IO_SLOT
J 1
(-1350 -1250);
DISPLAY 0.744681 (-1350 -1250);
DISPLAY INVISIBLE (-1350 -1250);
FORCEPROP 1 LAST PATH I14
J 0
(-1050 -1325);
DISPLAY 0.872340 (-1050 -1325);
PAINT AQUA (-1050 -1325);
DISPLAY INVISIBLE (-1050 -1325);
FORCEADD Q_RES..2
(-1125 -1000);
FORCEPROP 1 LAST PART_NUMBER CS21002FB06
J 0
(-1085 -1125);
DISPLAY 0.638298 (-1085 -1125);
DISPLAY INVISIBLE (-1085 -1125);
FORCEPROP 1 LAST VALUE 1K
J 0
(-1080 -925);
DISPLAY 0.638298 (-1080 -925);
FORCEPROP 1 LAST PACK_TYPE 0402LF
J 0
(-1085 -1175);
DISPLAY 0.638298 (-1085 -1175);
FORCEPROP 1 LAST WATTAGE 1/16W
J 0
(-1085 -1025);
DISPLAY 0.638298 (-1085 -1025);
FORCEPROP 1 LAST MATERIAL EMPTY
J 0
(-1085 -1075);
DISPLAY 0.638298 (-1085 -1075);
PAINT RED (-1085 -1075);
FORCEPROP 1 LAST TOLERANCE 1%
J 0
(-1080 -975);
DISPLAY 0.638298 (-1080 -975);
FORCEPROP 1 LAST $LOCATION R4646
J 0
(-1080 -875);
DISPLAY 0.978723 (-1080 -875);
FORCEPROP 1 LASTPIN (-1125 -900) $PN 1
J 0
(-1120 -938);
DISPLAY 0.787234 (-1120 -938);
PAINT MONO (-1120 -938);
FORCEPROP 1 LASTPIN (-1125 -1100) $PN 2
J 0
(-1120 -1090);
DISPLAY 0.787234 (-1120 -1090);
PAINT MONO (-1120 -1090);
FORCEPROP 2 LAST CDS_LIB pure_quanta
J 0
(-1125 -1000);
DISPLAY INVISIBLE (-1125 -1000);
FORCEPROP 1 LAST PATH I15
J 0
(-1075 -825);
DISPLAY 0.978723 (-1075 -825);
PAINT WHITE (-1075 -825);
DISPLAY INVISIBLE (-1075 -825);
FORCEPROP 0 LAST CDS_LOCATION R4646
J 0
(-1075 -825);
DISPLAY 1.021277 (-1075 -825);
DISPLAY INVISIBLE (-1075 -825);
FORCEPROP 0 LAST $SEC 1
J 0
(-1075 -825);
DISPLAY 0.680851 (-1075 -825);
PAINT MONO (-1075 -825);
DISPLAY INVISIBLE (-1075 -825);
FORCEPROP 0 LAST CDS_SEC 1
J 0
(-1075 -825);
DISPLAY 1.021277 (-1075 -825);
DISPLAY INVISIBLE (-1075 -825);
FORCEADD Q_RES..2
(-1125 -450);
FORCEPROP 1 LAST PART_NUMBER CS21002FB06
J 0
(-1085 -575);
DISPLAY 0.638298 (-1085 -575);
DISPLAY INVISIBLE (-1085 -575);
FORCEPROP 1 LAST WATTAGE 1/16W
J 0
(-1085 -475);
DISPLAY 0.638298 (-1085 -475);
FORCEPROP 1 LAST PACK_TYPE 0402LF
J 0
(-1085 -625);
DISPLAY 0.638298 (-1085 -625);
FORCEPROP 1 LAST VALUE 1K
J 0
(-1080 -375);
DISPLAY 0.638298 (-1080 -375);
FORCEPROP 1 LAST TOLERANCE 1%
J 0
(-1080 -425);
DISPLAY 0.638298 (-1080 -425);
FORCEPROP 1 LAST MATERIAL EMPTY
J 0
(-1085 -525);
DISPLAY 0.638298 (-1085 -525);
PAINT RED (-1085 -525);
FORCEPROP 1 LAST $LOCATION R4645
J 0
(-1080 -325);
DISPLAY 0.978723 (-1080 -325);
FORCEPROP 1 LASTPIN (-1125 -350) $PN 1
J 0
(-1120 -388);
DISPLAY 0.787234 (-1120 -388);
PAINT MONO (-1120 -388);
FORCEPROP 1 LASTPIN (-1125 -550) $PN 2
J 0
(-1120 -540);
DISPLAY 0.787234 (-1120 -540);
PAINT MONO (-1120 -540);
FORCEPROP 2 LAST CDS_LIB pure_quanta
J 0
(-1125 -450);
DISPLAY INVISIBLE (-1125 -450);
FORCEPROP 1 LAST PATH I16
J 0
(-1075 -275);
DISPLAY 0.978723 (-1075 -275);
PAINT WHITE (-1075 -275);
DISPLAY INVISIBLE (-1075 -275);
FORCEPROP 0 LAST CDS_LOCATION R4645
J 0
(-1075 -275);
DISPLAY 1.021277 (-1075 -275);
DISPLAY INVISIBLE (-1075 -275);
FORCEPROP 0 LAST $SEC 1
J 0
(-1075 -275);
DISPLAY 0.680851 (-1075 -275);
PAINT MONO (-1075 -275);
DISPLAY INVISIBLE (-1075 -275);
FORCEPROP 0 LAST CDS_SEC 1
J 0
(-1075 -275);
DISPLAY 1.021277 (-1075 -275);
DISPLAY INVISIBLE (-1075 -275);
FORCEADD OFFPAGE..2
(-475 -725);
FORCEPROP 2 LAST $XR0 167 
J 0
(-286 -725);
DISPLAY 0.638298 (-286 -725);
PAINT MONO (-286 -725);
FORCEPROP 2 LAST CDS_LIB standard
J 0
(-475 -725);
DISPLAY INVISIBLE (-475 -725);
FORCEPROP 1 LAST OFFPAGE TRUE
J 0
(-150 -850);
DISPLAY 0.872340 (-150 -850);
PAINT GREEN (-150 -850);
DISPLAY INVISIBLE (-150 -850);
FORCEPROP 1 LAST COMMENT_BODY TRUE
J 0
(-520 -820);
DISPLAY 0.872340 (-520 -820);
PAINT GREEN (-520 -820);
DISPLAY INVISIBLE (-520 -820);
FORCEPROP 2 LAST PATH I17
J 0
(-275 -675);
DISPLAY 1.021277 (-275 -675);
DISPLAY INVISIBLE (-275 -675);
FORCEADD OFFPAGE..2
(-475 -675);
FORCEPROP 2 LAST $XR0 167 
J 0
(-286 -675);
DISPLAY 0.638298 (-286 -675);
PAINT MONO (-286 -675);
FORCEPROP 2 LAST CDS_LIB standard
J 0
(-475 -675);
DISPLAY INVISIBLE (-475 -675);
FORCEPROP 1 LAST OFFPAGE TRUE
J 0
(-150 -800);
DISPLAY 0.872340 (-150 -800);
PAINT GREEN (-150 -800);
DISPLAY INVISIBLE (-150 -800);
FORCEPROP 1 LAST COMMENT_BODY TRUE
J 0
(-520 -770);
DISPLAY 0.872340 (-520 -770);
PAINT GREEN (-520 -770);
DISPLAY INVISIBLE (-520 -770);
FORCEPROP 2 LAST PATH I18
J 0
(-275 -625);
DISPLAY 1.021277 (-275 -625);
DISPLAY INVISIBLE (-275 -625);
FORCEADD OFFPAGE..4
R 2
(-3950 -25);
FORCEPROP 2 LAST $XR0 167 
J 0
(-4202 -25);
DISPLAY 0.638298 (-4202 -25);
PAINT MONO (-4202 -25);
FORCEPROP 1 LAST COMMENT_BODY TRUE
J 2
(-3925 -125);
DISPLAY 0.872340 (-3925 -125);
PAINT GREEN (-3925 -125);
DISPLAY INVISIBLE (-3925 -125);
FORCEPROP 1 LAST OFFPAGE TRUE
J 2
(-4275 -150);
DISPLAY 0.872340 (-4275 -150);
PAINT GREEN (-4275 -150);
DISPLAY INVISIBLE (-4275 -150);
FORCEPROP 2 LAST CDS_LIB standard
J 0
(-3950 -25);
DISPLAY INVISIBLE (-3950 -25);
FORCEPROP 2 LAST PATH I19
J 0
(-4200 25);
DISPLAY 1.021277 (-4200 25);
DISPLAY INVISIBLE (-4200 25);
FORCEADD Q_RES..2
(-1550 -2475);
FORCEPROP 1 LAST PART_NUMBER CS21002FB06
J 0
(-1510 -2600);
DISPLAY 0.638298 (-1510 -2600);
DISPLAY INVISIBLE (-1510 -2600);
FORCEPROP 1 LAST MATERIAL CHIP
J 0
(-1510 -2550);
DISPLAY 0.638298 (-1510 -2550);
FORCEPROP 1 LAST PACK_TYPE 0402LF
J 0
(-1510 -2650);
DISPLAY 0.638298 (-1510 -2650);
FORCEPROP 1 LAST VALUE 1K
J 0
(-1505 -2400);
DISPLAY 0.638298 (-1505 -2400);
FORCEPROP 1 LAST TOLERANCE 1%
J 0
(-1505 -2450);
DISPLAY 0.638298 (-1505 -2450);
FORCEPROP 1 LAST WATTAGE 1/16W
J 0
(-1510 -2500);
DISPLAY 0.638298 (-1510 -2500);
FORCEPROP 2 LAST ROOM PCIE REDRIVER1_BOM2
J 0
(-1525 -2275);
DISPLAY 0.638298 (-1525 -2275);
FORCEPROP 1 LAST $LOCATION R4653
J 0
(-1505 -2350);
DISPLAY 0.978723 (-1505 -2350);
FORCEPROP 1 LASTPIN (-1550 -2375) $PN 1
J 0
(-1545 -2413);
DISPLAY 0.787234 (-1545 -2413);
PAINT MONO (-1545 -2413);
FORCEPROP 1 LASTPIN (-1550 -2575) $PN 2
J 0
(-1545 -2565);
DISPLAY 0.787234 (-1545 -2565);
PAINT MONO (-1545 -2565);
FORCEPROP 2 LAST CDS_LIB pure_quanta
J 0
(-1550 -2475);
DISPLAY INVISIBLE (-1550 -2475);
FORCEPROP 1 LAST PATH I2
J 0
(-1500 -2300);
DISPLAY 0.978723 (-1500 -2300);
PAINT WHITE (-1500 -2300);
DISPLAY INVISIBLE (-1500 -2300);
FORCEPROP 0 LAST CDS_LOCATION R4653
J 0
(-1500 -2300);
DISPLAY 1.021277 (-1500 -2300);
DISPLAY INVISIBLE (-1500 -2300);
FORCEPROP 0 LAST $SEC 1
J 0
(-1500 -2300);
DISPLAY 0.680851 (-1500 -2300);
PAINT MONO (-1500 -2300);
DISPLAY INVISIBLE (-1500 -2300);
FORCEPROP 0 LAST CDS_SEC 1
J 0
(-1500 -2300);
DISPLAY 1.021277 (-1500 -2300);
DISPLAY INVISIBLE (-1500 -2300);
FORCEADD OFFPAGE..4
R 2
(-3950 25);
FORCEPROP 2 LAST $XR0 167 
J 0
(-4202 25);
DISPLAY 0.638298 (-4202 25);
PAINT MONO (-4202 25);
FORCEPROP 1 LAST COMMENT_BODY TRUE
J 2
(-3925 -75);
DISPLAY 0.872340 (-3925 -75);
PAINT GREEN (-3925 -75);
DISPLAY INVISIBLE (-3925 -75);
FORCEPROP 1 LAST OFFPAGE TRUE
J 2
(-4275 -100);
DISPLAY 0.872340 (-4275 -100);
PAINT GREEN (-4275 -100);
DISPLAY INVISIBLE (-4275 -100);
FORCEPROP 2 LAST CDS_LIB standard
J 0
(-3950 25);
DISPLAY INVISIBLE (-3950 25);
FORCEPROP 2 LAST PATH I20
J 0
(-4200 75);
DISPLAY 1.021277 (-4200 75);
DISPLAY INVISIBLE (-4200 75);
FORCEADD OFFPAGE..4
R 2
(-3950 200);
FORCEPROP 2 LAST $XR0 166 
J 0
(-4202 200);
DISPLAY 0.638298 (-4202 200);
PAINT MONO (-4202 200);
FORCEPROP 1 LAST OFFPAGE TRUE
J 2
(-4275 75);
DISPLAY 0.872340 (-4275 75);
PAINT GREEN (-4275 75);
DISPLAY INVISIBLE (-4275 75);
FORCEPROP 1 LAST COMMENT_BODY TRUE
J 2
(-3925 100);
DISPLAY 0.872340 (-3925 100);
PAINT GREEN (-3925 100);
DISPLAY INVISIBLE (-3925 100);
FORCEPROP 2 LAST CDS_LIB standard
J 0
(-3950 200);
DISPLAY INVISIBLE (-3950 200);
FORCEPROP 2 LAST PATH I21
J 0
(-4200 250);
DISPLAY 1.021277 (-4200 250);
DISPLAY INVISIBLE (-4200 250);
FORCEADD OFFPAGE..4
R 2
(-3950 250);
FORCEPROP 2 LAST $XR0 166 
J 0
(-4202 250);
DISPLAY 0.638298 (-4202 250);
PAINT MONO (-4202 250);
FORCEPROP 1 LAST OFFPAGE TRUE
J 2
(-4275 125);
DISPLAY 0.872340 (-4275 125);
PAINT GREEN (-4275 125);
DISPLAY INVISIBLE (-4275 125);
FORCEPROP 1 LAST COMMENT_BODY TRUE
J 2
(-3925 150);
DISPLAY 0.872340 (-3925 150);
PAINT GREEN (-3925 150);
DISPLAY INVISIBLE (-3925 150);
FORCEPROP 2 LAST CDS_LIB standard
J 0
(-3950 250);
DISPLAY INVISIBLE (-3950 250);
FORCEPROP 2 LAST PATH I22
J 0
(-4200 300);
DISPLAY 1.021277 (-4200 300);
DISPLAY INVISIBLE (-4200 300);
FORCEADD OFFPAGE..4
R 2
(-3950 650);
FORCEPROP 2 LAST $XR0 167 
J 0
(-4202 650);
DISPLAY 0.638298 (-4202 650);
PAINT MONO (-4202 650);
FORCEPROP 2 LAST CDS_LIB standard
J 0
(-3950 650);
DISPLAY INVISIBLE (-3950 650);
FORCEPROP 1 LAST OFFPAGE TRUE
J 2
(-4275 525);
DISPLAY 0.872340 (-4275 525);
PAINT GREEN (-4275 525);
DISPLAY INVISIBLE (-4275 525);
FORCEPROP 1 LAST COMMENT_BODY TRUE
J 2
(-3925 550);
DISPLAY 0.872340 (-3925 550);
PAINT GREEN (-3925 550);
DISPLAY INVISIBLE (-3925 550);
FORCEPROP 2 LAST PATH I23
J 0
(-4200 700);
DISPLAY 1.021277 (-4200 700);
DISPLAY INVISIBLE (-4200 700);
FORCEADD OFFPAGE..4
R 2
(-3950 600);
FORCEPROP 2 LAST $XR0 167 
J 0
(-4202 600);
DISPLAY 0.638298 (-4202 600);
PAINT MONO (-4202 600);
FORCEPROP 2 LAST CDS_LIB standard
J 0
(-3950 600);
DISPLAY INVISIBLE (-3950 600);
FORCEPROP 1 LAST OFFPAGE TRUE
J 2
(-4275 475);
DISPLAY 0.872340 (-4275 475);
PAINT GREEN (-4275 475);
DISPLAY INVISIBLE (-4275 475);
FORCEPROP 1 LAST COMMENT_BODY TRUE
J 2
(-3925 500);
DISPLAY 0.872340 (-3925 500);
PAINT GREEN (-3925 500);
DISPLAY INVISIBLE (-3925 500);
FORCEPROP 2 LAST PATH I24
J 0
(-4200 650);
DISPLAY 1.021277 (-4200 650);
DISPLAY INVISIBLE (-4200 650);
FORCEADD OFFPAGE..4
R 2
(-3950 825);
FORCEPROP 2 LAST $XR0 166 
J 0
(-4202 825);
DISPLAY 0.638298 (-4202 825);
PAINT MONO (-4202 825);
FORCEPROP 1 LAST COMMENT_BODY TRUE
J 2
(-3925 725);
DISPLAY 0.872340 (-3925 725);
PAINT GREEN (-3925 725);
DISPLAY INVISIBLE (-3925 725);
FORCEPROP 1 LAST OFFPAGE TRUE
J 2
(-4275 700);
DISPLAY 0.872340 (-4275 700);
PAINT GREEN (-4275 700);
DISPLAY INVISIBLE (-4275 700);
FORCEPROP 2 LAST CDS_LIB standard
J 0
(-3950 825);
DISPLAY INVISIBLE (-3950 825);
FORCEPROP 2 LAST PATH I25
J 0
(-4200 875);
DISPLAY 1.021277 (-4200 875);
DISPLAY INVISIBLE (-4200 875);
FORCEADD OFFPAGE..4
R 2
(-3950 875);
FORCEPROP 2 LAST $XR0 166 
J 0
(-4202 875);
DISPLAY 0.638298 (-4202 875);
PAINT MONO (-4202 875);
FORCEPROP 1 LAST COMMENT_BODY TRUE
J 2
(-3925 775);
DISPLAY 0.872340 (-3925 775);
PAINT GREEN (-3925 775);
DISPLAY INVISIBLE (-3925 775);
FORCEPROP 1 LAST OFFPAGE TRUE
J 2
(-4275 750);
DISPLAY 0.872340 (-4275 750);
PAINT GREEN (-4275 750);
DISPLAY INVISIBLE (-4275 750);
FORCEPROP 2 LAST CDS_LIB standard
J 0
(-3950 875);
DISPLAY INVISIBLE (-3950 875);
FORCEPROP 2 LAST PATH I26
J 0
(-4200 925);
DISPLAY 1.021277 (-4200 925);
DISPLAY INVISIBLE (-4200 925);
FORCEADD Q_CAP..2
(-2825 25);
FORCEPROP 1 LAST PART_NUMBER CH4104K1B00
J 1
(-2800 -300);
DISPLAY 0.510638 (-2800 -300);
DISPLAY INVISIBLE (-2800 -300);
FORCEPROP 2 LAST ROOM PCIE REDRIVER1_BOM2
J 0
(-3175 -125);
DISPLAY 0.808511 (-3175 -125);
FORCEPROP 1 LAST MATERIAL EMPTY
J 0
(-2725 25);
DISPLAY 0.510638 (-2725 25);
FORCEPROP 1 LAST $LOCATION C2353
J 1
(-3000 25);
DISPLAY 0.510638 (-3000 25);
FORCEPROP 1 LASTPIN (-2925 25) $PN 1
J 0
(-2935 40);
DISPLAY 0.787234 (-2935 40);
PAINT MONO (-2935 40);
FORCEPROP 1 LASTPIN (-2725 25) $PN 2
J 0
(-2740 40);
DISPLAY 0.787234 (-2740 40);
PAINT MONO (-2740 40);
FORCEPROP 1 LAST PATH I27
J 0
(-2825 225);
DISPLAY 0.978723 (-2825 225);
PAINT WHITE (-2825 225);
DISPLAY INVISIBLE (-2825 225);
FORCEPROP 2 LAST CDS_LIB pure_quanta
J 0
(-2825 25);
DISPLAY INVISIBLE (-2825 25);
FORCEPROP 1 LAST PACK_TYPE 0402
J 1
(-2800 -275);
DISPLAY 0.638298 (-2800 -275);
DISPLAY INVISIBLE (-2800 -275);
FORCEPROP 1 LAST TOLERANCE 10%
J 2
(-2800 -225);
DISPLAY 0.638298 (-2800 -225);
DISPLAY INVISIBLE (-2800 -225);
FORCEPROP 1 LAST VALUE 0.1UF
J 2
(-2800 -175);
DISPLAY 0.638298 (-2800 -175);
DISPLAY INVISIBLE (-2800 -175);
FORCEPROP 1 LAST VOLTAGE 25V
J 0
(-2800 -175);
DISPLAY 0.638298 (-2800 -175);
DISPLAY INVISIBLE (-2800 -175);
FORCEPROP 0 LAST CDS_LOCATION C2353
J 0
(-2950 75);
DISPLAY 1.021277 (-2950 75);
DISPLAY INVISIBLE (-2950 75);
FORCEPROP 0 LAST $SEC 1
J 0
(-2950 75);
DISPLAY 0.680851 (-2950 75);
PAINT MONO (-2950 75);
DISPLAY INVISIBLE (-2950 75);
FORCEPROP 0 LAST CDS_SEC 1
J 0
(-2950 75);
DISPLAY 1.021277 (-2950 75);
DISPLAY INVISIBLE (-2950 75);
FORCEADD Q_CAP..2
(-2825 -25);
FORCEPROP 1 LAST PART_NUMBER CH4104K1B00
J 1
(-2800 -225);
DISPLAY 0.510638 (-2800 -225);
DISPLAY INVISIBLE (-2800 -225);
FORCEPROP 2 LAST ROOM PCIE REDRIVER1_BOM2
J 0
(-3175 -175);
DISPLAY 0.808511 (-3175 -175);
FORCEPROP 1 LAST MATERIAL EMPTY
J 0
(-2725 -25);
DISPLAY 0.510638 (-2725 -25);
FORCEPROP 1 LAST $LOCATION C2354
J 1
(-3000 -25);
DISPLAY 0.510638 (-3000 -25);
FORCEPROP 1 LASTPIN (-2925 -25) $PN 1
J 0
(-2935 -10);
DISPLAY 0.787234 (-2935 -10);
PAINT MONO (-2935 -10);
FORCEPROP 1 LASTPIN (-2725 -25) $PN 2
J 0
(-2740 -10);
DISPLAY 0.787234 (-2740 -10);
PAINT MONO (-2740 -10);
FORCEPROP 1 LAST PATH I28
J 0
(-2825 175);
DISPLAY 0.978723 (-2825 175);
PAINT WHITE (-2825 175);
DISPLAY INVISIBLE (-2825 175);
FORCEPROP 1 LAST TOLERANCE 10%
J 2
(-2800 -150);
DISPLAY 0.638298 (-2800 -150);
DISPLAY INVISIBLE (-2800 -150);
FORCEPROP 1 LAST PACK_TYPE 0402
J 1
(-2800 -200);
DISPLAY 0.638298 (-2800 -200);
DISPLAY INVISIBLE (-2800 -200);
FORCEPROP 2 LAST CDS_LIB pure_quanta
J 0
(-2825 -25);
DISPLAY INVISIBLE (-2825 -25);
FORCEPROP 1 LAST VALUE 0.1UF
J 2
(-2800 -100);
DISPLAY 0.638298 (-2800 -100);
DISPLAY INVISIBLE (-2800 -100);
FORCEPROP 1 LAST VOLTAGE 25V
J 0
(-2800 -100);
DISPLAY 0.638298 (-2800 -100);
DISPLAY INVISIBLE (-2800 -100);
FORCEPROP 0 LAST CDS_LOCATION C2354
J 0
(-2950 25);
DISPLAY 1.021277 (-2950 25);
DISPLAY INVISIBLE (-2950 25);
FORCEPROP 0 LAST $SEC 1
J 0
(-2950 25);
DISPLAY 0.680851 (-2950 25);
PAINT MONO (-2950 25);
DISPLAY INVISIBLE (-2950 25);
FORCEPROP 0 LAST CDS_SEC 1
J 0
(-2950 25);
DISPLAY 1.021277 (-2950 25);
DISPLAY INVISIBLE (-2950 25);
FORCEADD Q_CAP..2
(-2825 250);
FORCEPROP 1 LAST PART_NUMBER CH4104K1B00
J 1
(-2800 -75);
DISPLAY 0.510638 (-2800 -75);
DISPLAY INVISIBLE (-2800 -75);
FORCEPROP 2 LAST ROOM PCIE REDRIVER1_BOM1
J 0
(-3225 150);
DISPLAY 0.638298 (-3225 150);
FORCEPROP 1 LAST $LOCATION C1868
J 1
(-3000 250);
DISPLAY 0.510638 (-3000 250);
FORCEPROP 1 LASTPIN (-2925 250) $PN 1
J 0
(-2935 265);
DISPLAY 0.787234 (-2935 265);
PAINT MONO (-2935 265);
FORCEPROP 1 LASTPIN (-2725 250) $PN 2
J 0
(-2740 265);
DISPLAY 0.787234 (-2740 265);
PAINT MONO (-2740 265);
FORCEPROP 1 LAST VOLTAGE 25V
J 0
(-2800 50);
DISPLAY 0.638298 (-2800 50);
DISPLAY INVISIBLE (-2800 50);
FORCEPROP 1 LAST VALUE 0.1UF
J 2
(-2800 50);
DISPLAY 0.638298 (-2800 50);
DISPLAY INVISIBLE (-2800 50);
FORCEPROP 1 LAST TOLERANCE 10%
J 2
(-2800 0);
DISPLAY 0.638298 (-2800 0);
DISPLAY INVISIBLE (-2800 0);
FORCEPROP 1 LAST PACK_TYPE 0402
J 1
(-2800 -50);
DISPLAY 0.638298 (-2800 -50);
DISPLAY INVISIBLE (-2800 -50);
FORCEPROP 1 LAST MATERIAL X7R
J 0
(-2800 0);
DISPLAY 0.638298 (-2800 0);
DISPLAY INVISIBLE (-2800 0);
FORCEPROP 2 LAST CDS_LIB pure_quanta
J 0
(-2825 250);
DISPLAY INVISIBLE (-2825 250);
FORCEPROP 1 LAST PATH I29
J 0
(-2825 450);
DISPLAY 0.978723 (-2825 450);
PAINT WHITE (-2825 450);
DISPLAY INVISIBLE (-2825 450);
FORCEPROP 0 LAST CDS_LOCATION C1868
J 0
(-2950 300);
DISPLAY 1.021277 (-2950 300);
DISPLAY INVISIBLE (-2950 300);
FORCEPROP 0 LAST $SEC 1
J 0
(-2950 300);
DISPLAY 0.680851 (-2950 300);
PAINT MONO (-2950 300);
DISPLAY INVISIBLE (-2950 300);
FORCEPROP 0 LAST CDS_SEC 1
J 0
(-2950 300);
DISPLAY 1.021277 (-2950 300);
DISPLAY INVISIBLE (-2950 300);
FORCEADD UNIVERSAL_GND..1
(-1125 -2800);
FORCEPROP 3 LASTPIN (-1125 -2750) SIG_NAME GND\g
J 0
(-1115 -2740);
DISPLAY 0.659574 (-1115 -2740);
PAINT MONO (-1115 -2740);
DISPLAY INVISIBLE (-1115 -2740);
FORCEPROP 2 LAST ROOM IO_SLOT
J 1
(-1350 -2725);
DISPLAY 0.744681 (-1350 -2725);
DISPLAY INVISIBLE (-1350 -2725);
FORCEPROP 1 LAST HDL_POWER GND
J 1
(-1100 -2875);
DISPLAY 0.872340 (-1100 -2875);
PAINT GREEN (-1100 -2875);
DISPLAY INVISIBLE (-1100 -2875);
FORCEPROP 2 LAST CDS_LIB logical_power
J 0
(-1125 -2800);
DISPLAY INVISIBLE (-1125 -2800);
FORCEPROP 1 LAST PATH I3
J 0
(-1050 -2800);
DISPLAY 0.872340 (-1050 -2800);
PAINT AQUA (-1050 -2800);
DISPLAY INVISIBLE (-1050 -2800);
FORCEADD Q_CAP..2
(-2825 200);
FORCEPROP 1 LAST PART_NUMBER CH4104K1B00
J 1
(-2800 0);
DISPLAY 0.510638 (-2800 0);
DISPLAY INVISIBLE (-2800 0);
FORCEPROP 2 LAST ROOM PCIE REDRIVER1_BOM1
J 0
(-3225 100);
DISPLAY 0.638298 (-3225 100);
FORCEPROP 1 LAST $LOCATION C1869
J 1
(-3000 200);
DISPLAY 0.510638 (-3000 200);
FORCEPROP 1 LASTPIN (-2925 200) $PN 1
J 0
(-2935 215);
DISPLAY 0.787234 (-2935 215);
PAINT MONO (-2935 215);
FORCEPROP 1 LASTPIN (-2725 200) $PN 2
J 0
(-2740 215);
DISPLAY 0.787234 (-2740 215);
PAINT MONO (-2740 215);
FORCEPROP 1 LAST VOLTAGE 25V
J 0
(-2800 125);
DISPLAY 0.638298 (-2800 125);
DISPLAY INVISIBLE (-2800 125);
FORCEPROP 1 LAST VALUE 0.1UF
J 2
(-2800 125);
DISPLAY 0.638298 (-2800 125);
DISPLAY INVISIBLE (-2800 125);
FORCEPROP 2 LAST CDS_LIB pure_quanta
J 0
(-2825 200);
DISPLAY INVISIBLE (-2825 200);
FORCEPROP 1 LAST MATERIAL X7R
J 0
(-2800 75);
DISPLAY 0.638298 (-2800 75);
DISPLAY INVISIBLE (-2800 75);
FORCEPROP 1 LAST PACK_TYPE 0402
J 1
(-2800 25);
DISPLAY 0.638298 (-2800 25);
DISPLAY INVISIBLE (-2800 25);
FORCEPROP 1 LAST TOLERANCE 10%
J 2
(-2800 75);
DISPLAY 0.638298 (-2800 75);
DISPLAY INVISIBLE (-2800 75);
FORCEPROP 1 LAST PATH I30
J 0
(-2825 400);
DISPLAY 0.978723 (-2825 400);
PAINT WHITE (-2825 400);
DISPLAY INVISIBLE (-2825 400);
FORCEPROP 0 LAST CDS_LOCATION C1869
J 0
(-2950 250);
DISPLAY 1.021277 (-2950 250);
DISPLAY INVISIBLE (-2950 250);
FORCEPROP 0 LAST $SEC 1
J 0
(-2950 250);
DISPLAY 0.680851 (-2950 250);
PAINT MONO (-2950 250);
DISPLAY INVISIBLE (-2950 250);
FORCEPROP 0 LAST CDS_SEC 1
J 0
(-2950 250);
DISPLAY 1.021277 (-2950 250);
DISPLAY INVISIBLE (-2950 250);
FORCEADD Q_CAP..2
(-2825 650);
FORCEPROP 1 LAST PART_NUMBER CH4104K1B00
J 1
(-2800 325);
DISPLAY 0.510638 (-2800 325);
DISPLAY INVISIBLE (-2800 325);
FORCEPROP 2 LAST ROOM PCIE REDRIVER1_BOM2
J 0
(-2600 550);
DISPLAY 0.638298 (-2600 550);
FORCEPROP 1 LAST MATERIAL EMPTY
J 0
(-2700 650);
DISPLAY 0.404255 (-2700 650);
FORCEPROP 1 LAST $LOCATION C2351
J 1
(-3000 650);
DISPLAY 0.510638 (-3000 650);
FORCEPROP 1 LASTPIN (-2925 650) $PN 1
J 0
(-2935 665);
DISPLAY 0.787234 (-2935 665);
PAINT MONO (-2935 665);
FORCEPROP 1 LASTPIN (-2725 650) $PN 2
J 0
(-2740 665);
DISPLAY 0.787234 (-2740 665);
PAINT MONO (-2740 665);
FORCEPROP 1 LAST PATH I31
J 0
(-2825 850);
DISPLAY 0.978723 (-2825 850);
PAINT WHITE (-2825 850);
DISPLAY INVISIBLE (-2825 850);
FORCEPROP 1 LAST VOLTAGE 25V
J 0
(-2800 450);
DISPLAY 0.638298 (-2800 450);
DISPLAY INVISIBLE (-2800 450);
FORCEPROP 1 LAST VALUE 0.1UF
J 2
(-2800 450);
DISPLAY 0.638298 (-2800 450);
DISPLAY INVISIBLE (-2800 450);
FORCEPROP 1 LAST TOLERANCE 10%
J 2
(-2800 400);
DISPLAY 0.638298 (-2800 400);
DISPLAY INVISIBLE (-2800 400);
FORCEPROP 1 LAST PACK_TYPE 0402
J 1
(-2800 350);
DISPLAY 0.638298 (-2800 350);
DISPLAY INVISIBLE (-2800 350);
FORCEPROP 2 LAST CDS_LIB pure_quanta
J 0
(-2825 650);
DISPLAY INVISIBLE (-2825 650);
FORCEPROP 0 LAST CDS_LOCATION C2351
J 0
(-2925 700);
DISPLAY 1.021277 (-2925 700);
DISPLAY INVISIBLE (-2925 700);
FORCEPROP 0 LAST $SEC 1
J 0
(-2925 700);
DISPLAY 0.680851 (-2925 700);
PAINT MONO (-2925 700);
DISPLAY INVISIBLE (-2925 700);
FORCEPROP 0 LAST CDS_SEC 1
J 0
(-2925 700);
DISPLAY 1.021277 (-2925 700);
DISPLAY INVISIBLE (-2925 700);
FORCEADD Q_CAP..2
(-2825 600);
FORCEPROP 1 LAST PART_NUMBER CH4104K1B00
J 1
(-2825 850);
DISPLAY 0.510638 (-2825 850);
DISPLAY INVISIBLE (-2825 850);
FORCEPROP 2 LAST ROOM PCIE REDRIVER1_BOM2
J 0
(-2600 600);
DISPLAY 0.638298 (-2600 600);
FORCEPROP 1 LAST MATERIAL EMPTY
J 0
(-2700 600);
DISPLAY 0.404255 (-2700 600);
FORCEPROP 1 LAST VOLTAGE 25V
J 0
(-2775 725);
DISPLAY 0.638298 (-2775 725);
FORCEPROP 1 LAST VALUE 0.1UF
J 2
(-2775 725);
DISPLAY 0.638298 (-2775 725);
FORCEPROP 1 LAST $LOCATION C2352
J 1
(-3000 600);
DISPLAY 0.510638 (-3000 600);
FORCEPROP 1 LASTPIN (-2925 600) $PN 1
J 0
(-2935 615);
DISPLAY 0.787234 (-2935 615);
PAINT MONO (-2935 615);
FORCEPROP 1 LASTPIN (-2725 600) $PN 2
J 0
(-2740 615);
DISPLAY 0.787234 (-2740 615);
PAINT MONO (-2740 615);
FORCEPROP 1 LAST PATH I32
J 0
(-2825 800);
DISPLAY 0.978723 (-2825 800);
PAINT WHITE (-2825 800);
DISPLAY INVISIBLE (-2825 800);
FORCEPROP 2 LAST CDS_LIB pure_quanta
J 0
(-2825 600);
DISPLAY INVISIBLE (-2825 600);
FORCEPROP 1 LAST PACK_TYPE 0402
J 1
(-2875 750);
DISPLAY 0.638298 (-2875 750);
DISPLAY INVISIBLE (-2875 750);
FORCEPROP 1 LAST TOLERANCE 10%
J 2
(-2700 750);
DISPLAY 0.638298 (-2700 750);
DISPLAY INVISIBLE (-2700 750);
FORCEPROP 0 LAST CDS_LOCATION C2352
J 0
(-2800 900);
DISPLAY 1.021277 (-2800 900);
DISPLAY INVISIBLE (-2800 900);
FORCEPROP 0 LAST $SEC 1
J 0
(-2800 900);
DISPLAY 0.680851 (-2800 900);
PAINT MONO (-2800 900);
DISPLAY INVISIBLE (-2800 900);
FORCEPROP 0 LAST CDS_SEC 1
J 0
(-2800 900);
DISPLAY 1.021277 (-2800 900);
DISPLAY INVISIBLE (-2800 900);
FORCEADD Q_CAP..2
(-2825 875);
FORCEPROP 1 LAST PART_NUMBER CH4104K1B00
J 1
(-2800 550);
DISPLAY 0.510638 (-2800 550);
DISPLAY INVISIBLE (-2800 550);
FORCEPROP 2 LAST ROOM PCIE REDRIVER1_BOM1
J 0
(-3200 750);
DISPLAY 0.638298 (-3200 750);
FORCEPROP 1 LAST $LOCATION C1870
J 1
(-3000 875);
DISPLAY 0.510638 (-3000 875);
FORCEPROP 1 LASTPIN (-2925 875) $PN 1
J 0
(-2935 890);
DISPLAY 0.787234 (-2935 890);
PAINT MONO (-2935 890);
FORCEPROP 1 LASTPIN (-2725 875) $PN 2
J 0
(-2740 890);
DISPLAY 0.787234 (-2740 890);
PAINT MONO (-2740 890);
FORCEPROP 1 LAST VOLTAGE 25V
J 0
(-2800 675);
DISPLAY 0.638298 (-2800 675);
DISPLAY INVISIBLE (-2800 675);
FORCEPROP 1 LAST VALUE 0.1UF
J 2
(-2800 675);
DISPLAY 0.638298 (-2800 675);
DISPLAY INVISIBLE (-2800 675);
FORCEPROP 1 LAST TOLERANCE 10%
J 2
(-2800 625);
DISPLAY 0.638298 (-2800 625);
DISPLAY INVISIBLE (-2800 625);
FORCEPROP 1 LAST PACK_TYPE 0402
J 1
(-2800 575);
DISPLAY 0.638298 (-2800 575);
DISPLAY INVISIBLE (-2800 575);
FORCEPROP 1 LAST MATERIAL X7R
J 0
(-2800 625);
DISPLAY 0.638298 (-2800 625);
DISPLAY INVISIBLE (-2800 625);
FORCEPROP 2 LAST CDS_LIB pure_quanta
J 0
(-2825 875);
DISPLAY INVISIBLE (-2825 875);
FORCEPROP 1 LAST PATH I33
J 0
(-2825 1075);
DISPLAY 0.978723 (-2825 1075);
PAINT WHITE (-2825 1075);
DISPLAY INVISIBLE (-2825 1075);
FORCEPROP 0 LAST CDS_LOCATION C1870
J 0
(-2925 925);
DISPLAY 1.021277 (-2925 925);
DISPLAY INVISIBLE (-2925 925);
FORCEPROP 0 LAST $SEC 1
J 0
(-2925 925);
DISPLAY 0.680851 (-2925 925);
PAINT MONO (-2925 925);
DISPLAY INVISIBLE (-2925 925);
FORCEPROP 0 LAST CDS_SEC 1
J 0
(-2925 925);
DISPLAY 1.021277 (-2925 925);
DISPLAY INVISIBLE (-2925 925);
FORCEADD Q_CAP..2
(-2825 825);
FORCEPROP 1 LAST PART_NUMBER CH4104K1B00
J 1
(-2825 1075);
DISPLAY 0.510638 (-2825 1075);
DISPLAY INVISIBLE (-2825 1075);
FORCEPROP 1 LAST PACK_TYPE 0402
J 1
(-2875 975);
DISPLAY 0.638298 (-2875 975);
FORCEPROP 1 LAST VALUE 0.1UF
J 2
(-2800 1025);
DISPLAY 0.638298 (-2800 1025);
FORCEPROP 2 LAST ROOM PCIE REDRIVER1_BOM1
J 0
(-3200 775);
DISPLAY 0.638298 (-3200 775);
FORCEPROP 1 LAST TOLERANCE 10%
J 2
(-2700 975);
DISPLAY 0.638298 (-2700 975);
FORCEPROP 1 LAST VOLTAGE 25V
J 0
(-2800 1025);
DISPLAY 0.638298 (-2800 1025);
FORCEPROP 1 LAST MATERIAL X7R
J 0
(-2700 1025);
DISPLAY 0.638298 (-2700 1025);
FORCEPROP 1 LAST $LOCATION C1871
J 1
(-3000 825);
DISPLAY 0.510638 (-3000 825);
FORCEPROP 1 LASTPIN (-2925 825) $PN 1
J 0
(-2935 840);
DISPLAY 0.787234 (-2935 840);
PAINT MONO (-2935 840);
FORCEPROP 1 LASTPIN (-2725 825) $PN 2
J 0
(-2740 840);
DISPLAY 0.787234 (-2740 840);
PAINT MONO (-2740 840);
FORCEPROP 2 LAST CDS_LIB pure_quanta
J 0
(-2825 825);
DISPLAY INVISIBLE (-2825 825);
FORCEPROP 1 LAST PATH I34
J 0
(-2825 1025);
DISPLAY 0.978723 (-2825 1025);
PAINT WHITE (-2825 1025);
DISPLAY INVISIBLE (-2825 1025);
FORCEPROP 0 LAST CDS_LOCATION C1871
J 0
(-2800 1125);
DISPLAY 1.021277 (-2800 1125);
DISPLAY INVISIBLE (-2800 1125);
FORCEPROP 0 LAST $SEC 1
J 0
(-2800 1125);
DISPLAY 0.680851 (-2800 1125);
PAINT MONO (-2800 1125);
DISPLAY INVISIBLE (-2800 1125);
FORCEPROP 0 LAST CDS_SEC 1
J 0
(-2800 1125);
DISPLAY 1.021277 (-2800 1125);
DISPLAY INVISIBLE (-2800 1125);
FORCEADD Q_RES..1
(-2725 1875);
FORCEPROP 1 LAST PART_NUMBER CS00002JB13
J 0
(-3000 1750);
DISPLAY 0.723404 (-3000 1750);
PAINT WHITE (-3000 1750);
DISPLAY INVISIBLE (-3000 1750);
FORCEPROP 2 LAST ROOM PCIE REDRIVER1_BOM2
J 0
(-2975 1725);
DISPLAY 0.638298 (-2975 1725);
FORCEPROP 1 LAST MATERIAL EMPTY
J 0
(-2550 1875);
DISPLAY 0.574468 (-2550 1875);
FORCEPROP 1 LAST VALUE 0
J 2
(-2575 1875);
DISPLAY 0.574468 (-2575 1875);
FORCEPROP 1 LAST PACK_TYPE 0402LF
J 0
(-2425 1875);
DISPLAY 0.574468 (-2425 1875);
FORCEPROP 1 LAST $LOCATION R4666
J 0
(-2975 1875);
DISPLAY 0.787234 (-2975 1875);
FORCEPROP 1 LASTPIN (-2825 1875) $PN 1
J 0
(-2813 1887);
DISPLAY 0.787234 (-2813 1887);
PAINT MONO (-2813 1887);
FORCEPROP 1 LASTPIN (-2625 1875) $PN 2
J 0
(-2663 1887);
DISPLAY 0.787234 (-2663 1887);
PAINT MONO (-2663 1887);
FORCEPROP 1 LAST PATH I35
J 0
(-2775 2025);
DISPLAY 0.978723 (-2775 2025);
PAINT WHITE (-2775 2025);
DISPLAY INVISIBLE (-2775 2025);
FORCEPROP 2 LAST CDS_LIB pure_quanta
J 0
(-2725 1875);
DISPLAY INVISIBLE (-2725 1875);
FORCEPROP 1 LAST WATTAGE 1/16W
J 2
(-2650 1800);
DISPLAY 0.723404 (-2650 1800);
PAINT SKYBLUE (-2650 1800);
DISPLAY INVISIBLE (-2650 1800);
FORCEPROP 1 LAST TOLERANCE 5%
J 0
(-2925 1800);
DISPLAY 0.723404 (-2925 1800);
PAINT SKYBLUE (-2925 1800);
DISPLAY INVISIBLE (-2925 1800);
FORCEPROP 0 LAST CDS_LOCATION R4666
J 0
(-2425 1925);
DISPLAY 1.021277 (-2425 1925);
DISPLAY INVISIBLE (-2425 1925);
FORCEPROP 0 LAST $SEC 1
J 0
(-2425 1925);
DISPLAY 0.680851 (-2425 1925);
PAINT MONO (-2425 1925);
DISPLAY INVISIBLE (-2425 1925);
FORCEPROP 0 LAST CDS_SEC 1
J 0
(-2425 1925);
DISPLAY 1.021277 (-2425 1925);
DISPLAY INVISIBLE (-2425 1925);
FORCEADD Q_RES..1
(-2725 1925);
FORCEPROP 1 LAST PART_NUMBER CS00002JB13
J 0
(-3000 1800);
DISPLAY 0.723404 (-3000 1800);
PAINT WHITE (-3000 1800);
DISPLAY INVISIBLE (-3000 1800);
FORCEPROP 2 LAST ROOM PCIE REDRIVER1_BOM2
J 0
(-2975 1775);
DISPLAY 0.638298 (-2975 1775);
FORCEPROP 1 LAST VALUE 0
J 2
(-2575 1925);
DISPLAY 0.574468 (-2575 1925);
FORCEPROP 1 LAST MATERIAL EMPTY
J 0
(-2550 1925);
DISPLAY 0.574468 (-2550 1925);
FORCEPROP 1 LAST PACK_TYPE 0402LF
J 0
(-2425 1925);
DISPLAY 0.574468 (-2425 1925);
FORCEPROP 1 LAST $LOCATION R4665
J 0
(-2975 1925);
DISPLAY 0.787234 (-2975 1925);
FORCEPROP 1 LASTPIN (-2825 1925) $PN 1
J 0
(-2813 1937);
DISPLAY 0.787234 (-2813 1937);
PAINT MONO (-2813 1937);
FORCEPROP 1 LASTPIN (-2625 1925) $PN 2
J 0
(-2663 1937);
DISPLAY 0.787234 (-2663 1937);
PAINT MONO (-2663 1937);
FORCEPROP 1 LAST PATH I36
J 0
(-2775 2075);
DISPLAY 0.978723 (-2775 2075);
PAINT WHITE (-2775 2075);
DISPLAY INVISIBLE (-2775 2075);
FORCEPROP 2 LAST CDS_LIB pure_quanta
J 0
(-2725 1925);
DISPLAY INVISIBLE (-2725 1925);
FORCEPROP 1 LAST WATTAGE 1/16W
J 2
(-2650 1850);
DISPLAY 0.723404 (-2650 1850);
PAINT SKYBLUE (-2650 1850);
DISPLAY INVISIBLE (-2650 1850);
FORCEPROP 1 LAST TOLERANCE 5%
J 0
(-2925 1850);
DISPLAY 0.723404 (-2925 1850);
PAINT SKYBLUE (-2925 1850);
DISPLAY INVISIBLE (-2925 1850);
FORCEPROP 0 LAST CDS_LOCATION R4665
J 0
(-2425 1975);
DISPLAY 1.021277 (-2425 1975);
DISPLAY INVISIBLE (-2425 1975);
FORCEPROP 0 LAST $SEC 1
J 0
(-2425 1975);
DISPLAY 0.680851 (-2425 1975);
PAINT MONO (-2425 1975);
DISPLAY INVISIBLE (-2425 1975);
FORCEPROP 0 LAST CDS_SEC 1
J 0
(-2425 1975);
DISPLAY 1.021277 (-2425 1975);
DISPLAY INVISIBLE (-2425 1975);
FORCEADD OFFPAGE..4
R 2
(-4225 2200);
FORCEPROP 2 LAST $XR0 143 
J 0
(-4477 2200);
DISPLAY 0.638298 (-4477 2200);
PAINT MONO (-4477 2200);
FORCEPROP 2 LAST CDS_LIB standard
J 0
(-4225 2200);
DISPLAY INVISIBLE (-4225 2200);
FORCEPROP 1 LAST OFFPAGE TRUE
J 2
(-4550 2075);
DISPLAY 0.872340 (-4550 2075);
PAINT GREEN (-4550 2075);
DISPLAY INVISIBLE (-4550 2075);
FORCEPROP 1 LAST COMMENT_BODY TRUE
J 2
(-4200 2100);
DISPLAY 0.872340 (-4200 2100);
PAINT GREEN (-4200 2100);
DISPLAY INVISIBLE (-4200 2100);
FORCEPROP 2 LAST PATH I37
J 0
(-4475 2250);
DISPLAY 1.021277 (-4475 2250);
DISPLAY INVISIBLE (-4475 2250);
FORCEADD OFFPAGE..4
R 2
(-4225 2150);
FORCEPROP 2 LAST $XR0 143 
J 0
(-4477 2150);
DISPLAY 0.638298 (-4477 2150);
PAINT MONO (-4477 2150);
FORCEPROP 2 LAST CDS_LIB standard
J 0
(-4225 2150);
DISPLAY INVISIBLE (-4225 2150);
FORCEPROP 1 LAST OFFPAGE TRUE
J 2
(-4550 2025);
DISPLAY 0.872340 (-4550 2025);
PAINT GREEN (-4550 2025);
DISPLAY INVISIBLE (-4550 2025);
FORCEPROP 1 LAST COMMENT_BODY TRUE
J 2
(-4200 2050);
DISPLAY 0.872340 (-4200 2050);
PAINT GREEN (-4200 2050);
DISPLAY INVISIBLE (-4200 2050);
FORCEPROP 2 LAST PATH I38
J 0
(-4475 2200);
DISPLAY 1.021277 (-4475 2200);
DISPLAY INVISIBLE (-4475 2200);
FORCEADD OFFPAGE..4
R 2
(-4225 2775);
FORCEPROP 2 LAST $XR0 240 
J 0
(-4477 2775);
DISPLAY 0.638298 (-4477 2775);
PAINT MONO (-4477 2775);
FORCEPROP 2 LAST CDS_LIB standard
J 0
(-4225 2775);
DISPLAY INVISIBLE (-4225 2775);
FORCEPROP 1 LAST OFFPAGE TRUE
J 2
(-4550 2650);
DISPLAY 0.872340 (-4550 2650);
PAINT GREEN (-4550 2650);
DISPLAY INVISIBLE (-4550 2650);
FORCEPROP 1 LAST COMMENT_BODY TRUE
J 2
(-4200 2675);
DISPLAY 0.872340 (-4200 2675);
PAINT GREEN (-4200 2675);
DISPLAY INVISIBLE (-4200 2675);
FORCEPROP 2 LAST PATH I39
J 0
(-4475 2825);
DISPLAY 1.021277 (-4475 2825);
DISPLAY INVISIBLE (-4475 2825);
FORCEADD Q_RES..2
(-1125 -2475);
FORCEPROP 1 LAST PART_NUMBER CS21002FB06
J 0
(-1085 -2600);
DISPLAY 0.638298 (-1085 -2600);
DISPLAY INVISIBLE (-1085 -2600);
FORCEPROP 2 LAST ROOM PCIE REDRIVER1_BOM2
J 0
(-1075 -2300);
DISPLAY 0.638298 (-1075 -2300);
FORCEPROP 1 LAST MATERIAL CHIP
J 0
(-1085 -2550);
DISPLAY 0.638298 (-1085 -2550);
FORCEPROP 1 LAST TOLERANCE 1%
J 0
(-1080 -2450);
DISPLAY 0.638298 (-1080 -2450);
FORCEPROP 1 LAST PACK_TYPE 0402LF
J 0
(-1085 -2650);
DISPLAY 0.638298 (-1085 -2650);
FORCEPROP 1 LAST WATTAGE 1/16W
J 0
(-1085 -2500);
DISPLAY 0.638298 (-1085 -2500);
FORCEPROP 1 LAST VALUE 1K
J 0
(-1080 -2400);
DISPLAY 0.638298 (-1080 -2400);
FORCEPROP 1 LAST $LOCATION R4647
J 0
(-1080 -2350);
DISPLAY 0.978723 (-1080 -2350);
FORCEPROP 1 LASTPIN (-1125 -2375) $PN 1
J 0
(-1120 -2413);
DISPLAY 0.787234 (-1120 -2413);
PAINT MONO (-1120 -2413);
FORCEPROP 1 LASTPIN (-1125 -2575) $PN 2
J 0
(-1120 -2565);
DISPLAY 0.787234 (-1120 -2565);
PAINT MONO (-1120 -2565);
FORCEPROP 2 LAST CDS_LIB pure_quanta
J 0
(-1125 -2475);
DISPLAY INVISIBLE (-1125 -2475);
FORCEPROP 1 LAST PATH I4
J 0
(-1075 -2300);
DISPLAY 0.978723 (-1075 -2300);
PAINT WHITE (-1075 -2300);
DISPLAY INVISIBLE (-1075 -2300);
FORCEPROP 0 LAST CDS_LOCATION R4647
J 0
(-1075 -2300);
DISPLAY 1.021277 (-1075 -2300);
DISPLAY INVISIBLE (-1075 -2300);
FORCEPROP 0 LAST $SEC 1
J 0
(-1075 -2300);
DISPLAY 0.680851 (-1075 -2300);
PAINT MONO (-1075 -2300);
DISPLAY INVISIBLE (-1075 -2300);
FORCEPROP 0 LAST CDS_SEC 1
J 0
(-1075 -2300);
DISPLAY 1.021277 (-1075 -2300);
DISPLAY INVISIBLE (-1075 -2300);
FORCEADD OFFPAGE..4
R 2
(-4225 2825);
FORCEPROP 2 LAST $XR0 240 
J 0
(-4477 2825);
DISPLAY 0.638298 (-4477 2825);
PAINT MONO (-4477 2825);
FORCEPROP 2 LAST CDS_LIB standard
J 0
(-4225 2825);
DISPLAY INVISIBLE (-4225 2825);
FORCEPROP 1 LAST OFFPAGE TRUE
J 2
(-4550 2700);
DISPLAY 0.872340 (-4550 2700);
PAINT GREEN (-4550 2700);
DISPLAY INVISIBLE (-4550 2700);
FORCEPROP 1 LAST COMMENT_BODY TRUE
J 2
(-4200 2725);
DISPLAY 0.872340 (-4200 2725);
PAINT GREEN (-4200 2725);
DISPLAY INVISIBLE (-4200 2725);
FORCEPROP 2 LAST PATH I40
J 0
(-4475 2875);
DISPLAY 1.021277 (-4475 2875);
DISPLAY INVISIBLE (-4475 2875);
FORCEADD Q_RES..1
(-2725 2200);
FORCEPROP 1 LAST PART_NUMBER CS00002JB13
J 0
(-3000 2075);
DISPLAY 0.723404 (-3000 2075);
PAINT WHITE (-3000 2075);
DISPLAY INVISIBLE (-3000 2075);
FORCEPROP 1 LAST MATERIAL CHIP
J 0
(-2550 2200);
DISPLAY 0.574468 (-2550 2200);
FORCEPROP 2 LAST ROOM PCIE REDRIVER1_BOM1
J 0
(-3000 2075);
DISPLAY 0.638298 (-3000 2075);
FORCEPROP 1 LAST VALUE 0
J 2
(-2575 2200);
DISPLAY 0.574468 (-2575 2200);
FORCEPROP 1 LAST PACK_TYPE 0402LF
J 0
(-2425 2200);
DISPLAY 0.574468 (-2425 2200);
FORCEPROP 1 LAST $LOCATION R4663
J 0
(-2975 2200);
DISPLAY 0.787234 (-2975 2200);
FORCEPROP 1 LASTPIN (-2825 2200) $PN 1
J 0
(-2813 2212);
DISPLAY 0.787234 (-2813 2212);
PAINT MONO (-2813 2212);
FORCEPROP 1 LASTPIN (-2625 2200) $PN 2
J 0
(-2663 2212);
DISPLAY 0.787234 (-2663 2212);
PAINT MONO (-2663 2212);
FORCEPROP 1 LAST TOLERANCE 5%
J 0
(-2925 2125);
DISPLAY 0.723404 (-2925 2125);
PAINT SKYBLUE (-2925 2125);
DISPLAY INVISIBLE (-2925 2125);
FORCEPROP 1 LAST WATTAGE 1/16W
J 2
(-2650 2125);
DISPLAY 0.723404 (-2650 2125);
PAINT SKYBLUE (-2650 2125);
DISPLAY INVISIBLE (-2650 2125);
FORCEPROP 2 LAST CDS_LIB pure_quanta
J 0
(-2725 2200);
DISPLAY INVISIBLE (-2725 2200);
FORCEPROP 1 LAST PATH I41
J 0
(-2775 2350);
DISPLAY 0.978723 (-2775 2350);
PAINT WHITE (-2775 2350);
DISPLAY INVISIBLE (-2775 2350);
FORCEPROP 0 LAST CDS_LOCATION R4663
J 0
(-2425 2250);
DISPLAY 1.021277 (-2425 2250);
DISPLAY INVISIBLE (-2425 2250);
FORCEPROP 0 LAST $SEC 1
J 0
(-2425 2250);
DISPLAY 0.680851 (-2425 2250);
PAINT MONO (-2425 2250);
DISPLAY INVISIBLE (-2425 2250);
FORCEPROP 0 LAST CDS_SEC 1
J 0
(-2425 2250);
DISPLAY 1.021277 (-2425 2250);
DISPLAY INVISIBLE (-2425 2250);
FORCEADD Q_RES..1
(-2725 2150);
FORCEPROP 1 LAST PART_NUMBER CS00002JB13
J 0
(-3000 2025);
DISPLAY 0.723404 (-3000 2025);
PAINT WHITE (-3000 2025);
DISPLAY INVISIBLE (-3000 2025);
FORCEPROP 2 LAST ROOM PCIE REDRIVER1_BOM1
J 0
(-3000 2050);
DISPLAY 0.638298 (-3000 2050);
FORCEPROP 1 LAST VALUE 0
J 2
(-2575 2150);
DISPLAY 0.574468 (-2575 2150);
FORCEPROP 1 LAST MATERIAL CHIP
J 0
(-2550 2150);
DISPLAY 0.574468 (-2550 2150);
FORCEPROP 1 LAST PACK_TYPE 0402LF
J 0
(-2425 2150);
DISPLAY 0.574468 (-2425 2150);
FORCEPROP 1 LAST $LOCATION R4664
J 0
(-2975 2150);
DISPLAY 0.787234 (-2975 2150);
FORCEPROP 1 LASTPIN (-2825 2150) $PN 1
J 0
(-2813 2162);
DISPLAY 0.787234 (-2813 2162);
PAINT MONO (-2813 2162);
FORCEPROP 1 LASTPIN (-2625 2150) $PN 2
J 0
(-2663 2162);
DISPLAY 0.787234 (-2663 2162);
PAINT MONO (-2663 2162);
FORCEPROP 2 LAST CDS_LIB pure_quanta
J 0
(-2725 2150);
DISPLAY INVISIBLE (-2725 2150);
FORCEPROP 1 LAST TOLERANCE 5%
J 0
(-2925 2075);
DISPLAY 0.723404 (-2925 2075);
PAINT SKYBLUE (-2925 2075);
DISPLAY INVISIBLE (-2925 2075);
FORCEPROP 1 LAST WATTAGE 1/16W
J 2
(-2650 2075);
DISPLAY 0.723404 (-2650 2075);
PAINT SKYBLUE (-2650 2075);
DISPLAY INVISIBLE (-2650 2075);
FORCEPROP 1 LAST PATH I42
J 0
(-2775 2300);
DISPLAY 0.978723 (-2775 2300);
PAINT WHITE (-2775 2300);
DISPLAY INVISIBLE (-2775 2300);
FORCEPROP 0 LAST CDS_LOCATION R4664
J 0
(-2425 2200);
DISPLAY 1.021277 (-2425 2200);
DISPLAY INVISIBLE (-2425 2200);
FORCEPROP 0 LAST $SEC 1
J 0
(-2425 2200);
DISPLAY 0.680851 (-2425 2200);
PAINT MONO (-2425 2200);
DISPLAY INVISIBLE (-2425 2200);
FORCEPROP 0 LAST CDS_SEC 1
J 0
(-2425 2200);
DISPLAY 1.021277 (-2425 2200);
DISPLAY INVISIBLE (-2425 2200);
FORCEADD Q_RES..1
(-2725 2500);
FORCEPROP 1 LAST PART_NUMBER CS00002JB13
J 0
(-3000 2375);
DISPLAY 0.723404 (-3000 2375);
PAINT WHITE (-3000 2375);
DISPLAY INVISIBLE (-3000 2375);
FORCEPROP 2 LAST ROOM PCIE REDRIVER1_BOM2
J 0
(-2425 2425);
DISPLAY 0.638298 (-2425 2425);
FORCEPROP 1 LAST PACK_TYPE 0402LF
J 0
(-2425 2500);
DISPLAY 0.574468 (-2425 2500);
FORCEPROP 1 LAST VALUE 0
J 2
(-2575 2500);
DISPLAY 0.574468 (-2575 2500);
FORCEPROP 1 LAST MATERIAL EMPTY
J 0
(-2550 2500);
DISPLAY 0.574468 (-2550 2500);
FORCEPROP 1 LAST $LOCATION R4662
J 0
(-2975 2500);
DISPLAY 0.787234 (-2975 2500);
FORCEPROP 1 LASTPIN (-2825 2500) $PN 1
J 0
(-2813 2512);
DISPLAY 0.787234 (-2813 2512);
PAINT MONO (-2813 2512);
FORCEPROP 1 LASTPIN (-2625 2500) $PN 2
J 0
(-2663 2512);
DISPLAY 0.787234 (-2663 2512);
PAINT MONO (-2663 2512);
FORCEPROP 1 LAST PATH I43
J 0
(-2775 2650);
DISPLAY 0.978723 (-2775 2650);
PAINT WHITE (-2775 2650);
DISPLAY INVISIBLE (-2775 2650);
FORCEPROP 2 LAST CDS_LIB pure_quanta
J 0
(-2725 2500);
DISPLAY INVISIBLE (-2725 2500);
FORCEPROP 1 LAST WATTAGE 1/16W
J 2
(-2650 2425);
DISPLAY 0.723404 (-2650 2425);
PAINT SKYBLUE (-2650 2425);
DISPLAY INVISIBLE (-2650 2425);
FORCEPROP 1 LAST TOLERANCE 5%
J 0
(-2925 2425);
DISPLAY 0.723404 (-2925 2425);
PAINT SKYBLUE (-2925 2425);
DISPLAY INVISIBLE (-2925 2425);
FORCEPROP 0 LAST CDS_LOCATION R4662
J 0
(-2425 2550);
DISPLAY 1.021277 (-2425 2550);
DISPLAY INVISIBLE (-2425 2550);
FORCEPROP 0 LAST $SEC 1
J 0
(-2425 2550);
DISPLAY 0.680851 (-2425 2550);
PAINT MONO (-2425 2550);
DISPLAY INVISIBLE (-2425 2550);
FORCEPROP 0 LAST CDS_SEC 1
J 0
(-2425 2550);
DISPLAY 1.021277 (-2425 2550);
DISPLAY INVISIBLE (-2425 2550);
FORCEADD Q_RES..1
(-2725 2550);
FORCEPROP 1 LAST PART_NUMBER CS00002JB13
J 0
(-3000 2425);
DISPLAY 0.723404 (-3000 2425);
PAINT WHITE (-3000 2425);
DISPLAY INVISIBLE (-3000 2425);
FORCEPROP 2 LAST ROOM PCIE REDRIVER1_BOM2
J 0
(-2425 2475);
DISPLAY 0.638298 (-2425 2475);
FORCEPROP 1 LAST PACK_TYPE 0402LF
J 0
(-2425 2550);
DISPLAY 0.574468 (-2425 2550);
FORCEPROP 1 LAST VALUE 0
J 2
(-2575 2550);
DISPLAY 0.574468 (-2575 2550);
FORCEPROP 1 LAST MATERIAL EMPTY
J 0
(-2550 2550);
DISPLAY 0.574468 (-2550 2550);
FORCEPROP 1 LAST $LOCATION R4661
J 0
(-2975 2550);
DISPLAY 0.787234 (-2975 2550);
FORCEPROP 1 LASTPIN (-2825 2550) $PN 1
J 0
(-2813 2562);
DISPLAY 0.787234 (-2813 2562);
PAINT MONO (-2813 2562);
FORCEPROP 1 LASTPIN (-2625 2550) $PN 2
J 0
(-2663 2562);
DISPLAY 0.787234 (-2663 2562);
PAINT MONO (-2663 2562);
FORCEPROP 1 LAST PATH I44
J 0
(-2775 2700);
DISPLAY 0.978723 (-2775 2700);
PAINT WHITE (-2775 2700);
DISPLAY INVISIBLE (-2775 2700);
FORCEPROP 2 LAST CDS_LIB pure_quanta
J 0
(-2725 2550);
DISPLAY INVISIBLE (-2725 2550);
FORCEPROP 1 LAST WATTAGE 1/16W
J 2
(-2650 2475);
DISPLAY 0.723404 (-2650 2475);
PAINT SKYBLUE (-2650 2475);
DISPLAY INVISIBLE (-2650 2475);
FORCEPROP 1 LAST TOLERANCE 5%
J 0
(-2925 2475);
DISPLAY 0.723404 (-2925 2475);
PAINT SKYBLUE (-2925 2475);
DISPLAY INVISIBLE (-2925 2475);
FORCEPROP 0 LAST CDS_LOCATION R4661
J 0
(-2425 2600);
DISPLAY 1.021277 (-2425 2600);
DISPLAY INVISIBLE (-2425 2600);
FORCEPROP 0 LAST $SEC 1
J 0
(-2425 2600);
DISPLAY 0.680851 (-2425 2600);
PAINT MONO (-2425 2600);
DISPLAY INVISIBLE (-2425 2600);
FORCEPROP 0 LAST CDS_SEC 1
J 0
(-2425 2600);
DISPLAY 1.021277 (-2425 2600);
DISPLAY INVISIBLE (-2425 2600);
FORCEADD Q_RES..1
(-2725 2775);
FORCEPROP 1 LAST PART_NUMBER CS00002JB13
J 0
(-3000 2650);
DISPLAY 0.723404 (-3000 2650);
PAINT WHITE (-3000 2650);
DISPLAY INVISIBLE (-3000 2650);
FORCEPROP 2 LAST ROOM PCIE REDRIVER1_BOM1
J 0
(-2975 2675);
DISPLAY 0.638298 (-2975 2675);
FORCEPROP 1 LAST PACK_TYPE 0402LF
J 0
(-2425 2775);
DISPLAY 0.574468 (-2425 2775);
FORCEPROP 1 LAST MATERIAL CHIP
J 0
(-2550 2775);
DISPLAY 0.574468 (-2550 2775);
FORCEPROP 1 LAST VALUE 0
J 2
(-2575 2775);
DISPLAY 0.574468 (-2575 2775);
FORCEPROP 1 LAST $LOCATION R4660
J 0
(-2975 2775);
DISPLAY 0.787234 (-2975 2775);
FORCEPROP 1 LASTPIN (-2825 2775) $PN 1
J 0
(-2813 2787);
DISPLAY 0.787234 (-2813 2787);
PAINT MONO (-2813 2787);
FORCEPROP 1 LASTPIN (-2625 2775) $PN 2
J 0
(-2663 2787);
DISPLAY 0.787234 (-2663 2787);
PAINT MONO (-2663 2787);
FORCEPROP 2 LAST CDS_LIB pure_quanta
J 0
(-2725 2775);
DISPLAY INVISIBLE (-2725 2775);
FORCEPROP 1 LAST TOLERANCE 5%
J 0
(-2925 2700);
DISPLAY 0.723404 (-2925 2700);
PAINT SKYBLUE (-2925 2700);
DISPLAY INVISIBLE (-2925 2700);
FORCEPROP 1 LAST WATTAGE 1/16W
J 2
(-2650 2700);
DISPLAY 0.723404 (-2650 2700);
PAINT SKYBLUE (-2650 2700);
DISPLAY INVISIBLE (-2650 2700);
FORCEPROP 1 LAST PATH I45
J 0
(-2775 2925);
DISPLAY 0.978723 (-2775 2925);
PAINT WHITE (-2775 2925);
DISPLAY INVISIBLE (-2775 2925);
FORCEPROP 0 LAST CDS_LOCATION R4660
J 0
(-2425 2825);
DISPLAY 1.021277 (-2425 2825);
DISPLAY INVISIBLE (-2425 2825);
FORCEPROP 0 LAST $SEC 1
J 0
(-2425 2825);
DISPLAY 0.680851 (-2425 2825);
PAINT MONO (-2425 2825);
DISPLAY INVISIBLE (-2425 2825);
FORCEPROP 0 LAST CDS_SEC 1
J 0
(-2425 2825);
DISPLAY 1.021277 (-2425 2825);
DISPLAY INVISIBLE (-2425 2825);
FORCEADD Q_RES..1
(-2725 2825);
FORCEPROP 1 LAST PART_NUMBER CS00002JB13
J 0
(-3000 2700);
DISPLAY 0.723404 (-3000 2700);
PAINT WHITE (-3000 2700);
DISPLAY INVISIBLE (-3000 2700);
FORCEPROP 2 LAST ROOM PCIE REDRIVER1_BOM1
J 0
(-2975 2725);
DISPLAY 0.638298 (-2975 2725);
FORCEPROP 1 LAST VALUE 0
J 2
(-2575 2825);
DISPLAY 0.574468 (-2575 2825);
FORCEPROP 1 LAST PACK_TYPE 0402LF
J 0
(-2425 2825);
DISPLAY 0.574468 (-2425 2825);
FORCEPROP 1 LAST MATERIAL CHIP
J 0
(-2550 2825);
DISPLAY 0.574468 (-2550 2825);
FORCEPROP 1 LAST $LOCATION R4659
J 0
(-2975 2825);
DISPLAY 0.787234 (-2975 2825);
FORCEPROP 1 LASTPIN (-2825 2825) $PN 1
J 0
(-2813 2837);
DISPLAY 0.787234 (-2813 2837);
PAINT MONO (-2813 2837);
FORCEPROP 1 LASTPIN (-2625 2825) $PN 2
J 0
(-2663 2837);
DISPLAY 0.787234 (-2663 2837);
PAINT MONO (-2663 2837);
FORCEPROP 1 LAST TOLERANCE 5%
J 0
(-2925 2750);
DISPLAY 0.723404 (-2925 2750);
PAINT SKYBLUE (-2925 2750);
DISPLAY INVISIBLE (-2925 2750);
FORCEPROP 1 LAST WATTAGE 1/16W
J 2
(-2650 2750);
DISPLAY 0.723404 (-2650 2750);
PAINT SKYBLUE (-2650 2750);
DISPLAY INVISIBLE (-2650 2750);
FORCEPROP 2 LAST CDS_LIB pure_quanta
J 0
(-2725 2825);
DISPLAY INVISIBLE (-2725 2825);
FORCEPROP 1 LAST PATH I46
J 0
(-2775 2975);
DISPLAY 0.978723 (-2775 2975);
PAINT WHITE (-2775 2975);
DISPLAY INVISIBLE (-2775 2975);
FORCEPROP 0 LAST CDS_LOCATION R4659
J 0
(-2425 2875);
DISPLAY 1.021277 (-2425 2875);
DISPLAY INVISIBLE (-2425 2875);
FORCEPROP 0 LAST $SEC 1
J 0
(-2425 2875);
DISPLAY 0.680851 (-2425 2875);
PAINT MONO (-2425 2875);
DISPLAY INVISIBLE (-2425 2875);
FORCEPROP 0 LAST CDS_SEC 1
J 0
(-2425 2875);
DISPLAY 1.021277 (-2425 2875);
DISPLAY INVISIBLE (-2425 2875);
FORCEADD OFFPAGE..2
(-1750 200);
FORCEPROP 2 LAST $XR0 240 
J 0
(-1561 200);
DISPLAY 0.638298 (-1561 200);
PAINT MONO (-1561 200);
FORCEPROP 2 LAST CDS_LIB standard
J 2
(-1750 200);
DISPLAY INVISIBLE (-1750 200);
FORCEPROP 1 LAST OFFPAGE TRUE
J 0
(-1425 75);
DISPLAY 0.872340 (-1425 75);
PAINT AQUA (-1425 75);
DISPLAY INVISIBLE (-1425 75);
FORCEPROP 1 LAST COMMENT_BODY TRUE
J 0
(-1795 105);
DISPLAY 0.872340 (-1795 105);
PAINT GREEN (-1795 105);
DISPLAY INVISIBLE (-1795 105);
FORCEPROP 2 LAST PATH I47
J 0
(-1550 250);
DISPLAY 1.021277 (-1550 250);
DISPLAY INVISIBLE (-1550 250);
FORCEADD OFFPAGE..2
(-1750 250);
FORCEPROP 2 LAST $XR0 240 
J 0
(-1561 250);
DISPLAY 0.638298 (-1561 250);
PAINT MONO (-1561 250);
FORCEPROP 2 LAST CDS_LIB standard
J 0
(-1750 250);
DISPLAY INVISIBLE (-1750 250);
FORCEPROP 1 LAST OFFPAGE TRUE
J 0
(-1425 125);
DISPLAY 0.872340 (-1425 125);
PAINT AQUA (-1425 125);
DISPLAY INVISIBLE (-1425 125);
FORCEPROP 1 LAST COMMENT_BODY TRUE
J 0
(-1795 155);
DISPLAY 0.872340 (-1795 155);
PAINT GREEN (-1795 155);
DISPLAY INVISIBLE (-1795 155);
FORCEPROP 2 LAST PATH I48
J 0
(-1550 300);
DISPLAY 1.021277 (-1550 300);
DISPLAY INVISIBLE (-1550 300);
FORCEADD OFFPAGE..2
(-1750 825);
FORCEPROP 2 LAST $XR0 143 
J 0
(-1561 825);
DISPLAY 0.638298 (-1561 825);
PAINT MONO (-1561 825);
FORCEPROP 1 LAST COMMENT_BODY TRUE
J 0
(-1795 730);
DISPLAY 0.872340 (-1795 730);
PAINT GREEN (-1795 730);
DISPLAY INVISIBLE (-1795 730);
FORCEPROP 1 LAST OFFPAGE TRUE
J 0
(-1425 700);
DISPLAY 0.872340 (-1425 700);
PAINT AQUA (-1425 700);
DISPLAY INVISIBLE (-1425 700);
FORCEPROP 2 LAST CDS_LIB standard
J 0
(-1750 825);
DISPLAY INVISIBLE (-1750 825);
FORCEPROP 2 LAST PATH I49
J 0
(-1550 875);
DISPLAY 1.021277 (-1550 875);
DISPLAY INVISIBLE (-1550 875);
FORCEADD OFFPAGE..2
(-475 -2200);
FORCEPROP 2 LAST $XR0 167 
J 0
(-286 -2200);
DISPLAY 0.638298 (-286 -2200);
PAINT MONO (-286 -2200);
FORCEPROP 1 LAST COMMENT_BODY TRUE
J 0
(-520 -2295);
DISPLAY 0.872340 (-520 -2295);
PAINT GREEN (-520 -2295);
DISPLAY INVISIBLE (-520 -2295);
FORCEPROP 1 LAST OFFPAGE TRUE
J 0
(-150 -2325);
DISPLAY 0.872340 (-150 -2325);
PAINT GREEN (-150 -2325);
DISPLAY INVISIBLE (-150 -2325);
FORCEPROP 2 LAST CDS_LIB standard
J 0
(-475 -2200);
DISPLAY INVISIBLE (-475 -2200);
FORCEPROP 2 LAST PATH I5
J 0
(-275 -2150);
DISPLAY 1.021277 (-275 -2150);
DISPLAY INVISIBLE (-275 -2150);
FORCEADD OFFPAGE..2
(-1750 875);
FORCEPROP 2 LAST $XR0 143 
J 0
(-1561 875);
DISPLAY 0.638298 (-1561 875);
PAINT MONO (-1561 875);
FORCEPROP 1 LAST COMMENT_BODY TRUE
J 0
(-1795 780);
DISPLAY 0.872340 (-1795 780);
PAINT GREEN (-1795 780);
DISPLAY INVISIBLE (-1795 780);
FORCEPROP 1 LAST OFFPAGE TRUE
J 0
(-1425 750);
DISPLAY 0.872340 (-1425 750);
PAINT AQUA (-1425 750);
DISPLAY INVISIBLE (-1425 750);
FORCEPROP 2 LAST CDS_LIB standard
J 2
(-1750 875);
DISPLAY INVISIBLE (-1750 875);
FORCEPROP 2 LAST PATH I50
J 0
(-1550 925);
DISPLAY 1.021277 (-1550 925);
DISPLAY INVISIBLE (-1550 925);
FORCEADD OFFPAGE..2
(-1450 1925);
FORCEPROP 2 LAST $XR0 167 
J 0
(-1261 1925);
DISPLAY 0.638298 (-1261 1925);
PAINT MONO (-1261 1925);
FORCEPROP 1 LAST COMMENT_BODY TRUE
J 0
(-1495 1830);
DISPLAY 0.872340 (-1495 1830);
PAINT GREEN (-1495 1830);
DISPLAY INVISIBLE (-1495 1830);
FORCEPROP 1 LAST OFFPAGE TRUE
J 0
(-1125 1800);
DISPLAY 0.872340 (-1125 1800);
PAINT AQUA (-1125 1800);
DISPLAY INVISIBLE (-1125 1800);
FORCEPROP 2 LAST CDS_LIB standard
J 0
(-1450 1925);
DISPLAY INVISIBLE (-1450 1925);
FORCEPROP 2 LAST PATH I51
J 0
(-1250 1975);
DISPLAY 1.021277 (-1250 1975);
DISPLAY INVISIBLE (-1250 1975);
FORCEADD UNIVERSAL_GND..1
(-825 850);
FORCEPROP 3 LASTPIN (-825 900) SIG_NAME GND\g
J 0
(-815 910);
DISPLAY 0.659574 (-815 910);
PAINT MONO (-815 910);
DISPLAY INVISIBLE (-815 910);
FORCEPROP 2 LAST CDS_LIB logical_power
J 0
(-825 850);
DISPLAY INVISIBLE (-825 850);
FORCEPROP 1 LAST HDL_POWER GND
J 1
(-800 775);
DISPLAY 0.872340 (-800 775);
PAINT GREEN (-800 775);
DISPLAY INVISIBLE (-800 775);
FORCEPROP 1 LAST PATH I52
J 0
(-750 850);
DISPLAY 0.872340 (-750 850);
PAINT AQUA (-750 850);
DISPLAY INVISIBLE (-750 850);
FORCEADD Q_RES..2
(-825 1150);
FORCEPROP 1 LAST PART_NUMBER CS21002FB06
J 0
(-785 1025);
DISPLAY 0.638298 (-785 1025);
DISPLAY INVISIBLE (-785 1025);
FORCEPROP 2 LAST ROOM PCIE REDRIVER1_BOM2
J 0
(-775 1325);
DISPLAY 0.638298 (-775 1325);
FORCEPROP 1 LAST PACK_TYPE 0402LF
J 0
(-785 975);
DISPLAY 0.638298 (-785 975);
FORCEPROP 1 LAST MATERIAL CHIP
J 0
(-785 1075);
DISPLAY 0.638298 (-785 1075);
FORCEPROP 1 LAST VALUE 1K
J 0
(-780 1225);
DISPLAY 0.638298 (-780 1225);
FORCEPROP 1 LAST TOLERANCE 1%
J 0
(-780 1175);
DISPLAY 0.638298 (-780 1175);
FORCEPROP 1 LAST WATTAGE 1/16W
J 0
(-785 1125);
DISPLAY 0.638298 (-785 1125);
FORCEPROP 1 LAST $LOCATION R3362
J 0
(-780 1275);
DISPLAY 0.978723 (-780 1275);
FORCEPROP 1 LASTPIN (-825 1250) $PN 1
J 0
(-820 1212);
DISPLAY 0.787234 (-820 1212);
PAINT MONO (-820 1212);
FORCEPROP 1 LASTPIN (-825 1050) $PN 2
J 0
(-820 1060);
DISPLAY 0.787234 (-820 1060);
PAINT MONO (-820 1060);
FORCEPROP 2 LAST CDS_LIB pure_quanta
J 0
(-825 1150);
DISPLAY INVISIBLE (-825 1150);
FORCEPROP 1 LAST PATH I53
J 0
(-775 1325);
DISPLAY 0.978723 (-775 1325);
PAINT WHITE (-775 1325);
DISPLAY INVISIBLE (-775 1325);
FORCEPROP 0 LAST CDS_LOCATION R3362
J 0
(-775 1325);
DISPLAY 1.021277 (-775 1325);
DISPLAY INVISIBLE (-775 1325);
FORCEPROP 0 LAST $SEC 1
J 0
(-775 1325);
DISPLAY 0.680851 (-775 1325);
PAINT MONO (-775 1325);
DISPLAY INVISIBLE (-775 1325);
FORCEPROP 0 LAST CDS_SEC 1
J 0
(-775 1325);
DISPLAY 1.021277 (-775 1325);
DISPLAY INVISIBLE (-775 1325);
FORCEADD OFFPAGE..2
(-1450 2200);
FORCEPROP 2 LAST $XR0 166 
J 0
(-1261 2200);
DISPLAY 0.638298 (-1261 2200);
PAINT MONO (-1261 2200);
FORCEPROP 2 LAST CDS_LIB standard
J 0
(-1450 2200);
DISPLAY INVISIBLE (-1450 2200);
FORCEPROP 1 LAST COMMENT_BODY TRUE
J 0
(-1495 2105);
DISPLAY 0.872340 (-1495 2105);
PAINT GREEN (-1495 2105);
DISPLAY INVISIBLE (-1495 2105);
FORCEPROP 1 LAST OFFPAGE TRUE
J 0
(-1125 2075);
DISPLAY 0.872340 (-1125 2075);
PAINT AQUA (-1125 2075);
DISPLAY INVISIBLE (-1125 2075);
FORCEPROP 2 LAST PATH I54
J 0
(-1250 2250);
DISPLAY 1.021277 (-1250 2250);
DISPLAY INVISIBLE (-1250 2250);
FORCEADD OFFPAGE..2
(-1450 2150);
FORCEPROP 2 LAST $XR0 166 
J 0
(-1261 2150);
DISPLAY 0.638298 (-1261 2150);
PAINT MONO (-1261 2150);
FORCEPROP 1 LAST OFFPAGE TRUE
J 0
(-1125 2025);
DISPLAY 0.872340 (-1125 2025);
PAINT AQUA (-1125 2025);
DISPLAY INVISIBLE (-1125 2025);
FORCEPROP 1 LAST COMMENT_BODY TRUE
J 0
(-1495 2055);
DISPLAY 0.872340 (-1495 2055);
PAINT GREEN (-1495 2055);
DISPLAY INVISIBLE (-1495 2055);
FORCEPROP 2 LAST CDS_LIB standard
J 0
(-1450 2150);
DISPLAY INVISIBLE (-1450 2150);
FORCEPROP 2 LAST PATH I55
J 0
(-1250 2200);
DISPLAY 1.021277 (-1250 2200);
DISPLAY INVISIBLE (-1250 2200);
FORCEADD OFFPAGE..2
(-1450 2500);
FORCEPROP 2 LAST $XR0 167 
J 0
(-1261 2500);
DISPLAY 0.638298 (-1261 2500);
PAINT MONO (-1261 2500);
FORCEPROP 1 LAST COMMENT_BODY TRUE
J 0
(-1495 2405);
DISPLAY 0.872340 (-1495 2405);
PAINT GREEN (-1495 2405);
DISPLAY INVISIBLE (-1495 2405);
FORCEPROP 1 LAST OFFPAGE TRUE
J 0
(-1125 2375);
DISPLAY 0.872340 (-1125 2375);
PAINT AQUA (-1125 2375);
DISPLAY INVISIBLE (-1125 2375);
FORCEPROP 2 LAST CDS_LIB standard
J 0
(-1450 2500);
DISPLAY INVISIBLE (-1450 2500);
FORCEPROP 2 LAST PATH I56
J 0
(-1250 2550);
DISPLAY 1.021277 (-1250 2550);
DISPLAY INVISIBLE (-1250 2550);
FORCEADD OFFPAGE..2
(-1450 2550);
FORCEPROP 2 LAST $XR0 167 
J 0
(-1261 2550);
DISPLAY 0.638298 (-1261 2550);
PAINT MONO (-1261 2550);
FORCEPROP 1 LAST COMMENT_BODY TRUE
J 0
(-1495 2455);
DISPLAY 0.872340 (-1495 2455);
PAINT GREEN (-1495 2455);
DISPLAY INVISIBLE (-1495 2455);
FORCEPROP 1 LAST OFFPAGE TRUE
J 0
(-1125 2425);
DISPLAY 0.872340 (-1125 2425);
PAINT AQUA (-1125 2425);
DISPLAY INVISIBLE (-1125 2425);
FORCEPROP 2 LAST CDS_LIB standard
J 0
(-1450 2550);
DISPLAY INVISIBLE (-1450 2550);
FORCEPROP 2 LAST PATH I57
J 0
(-1250 2600);
DISPLAY 1.021277 (-1250 2600);
DISPLAY INVISIBLE (-1250 2600);
FORCEADD OFFPAGE..2
(-1450 2775);
FORCEPROP 2 LAST $XR0 166 
J 0
(-1261 2775);
DISPLAY 0.638298 (-1261 2775);
PAINT MONO (-1261 2775);
FORCEPROP 2 LAST CDS_LIB standard
J 0
(-1450 2775);
DISPLAY INVISIBLE (-1450 2775);
FORCEPROP 1 LAST COMMENT_BODY TRUE
J 0
(-1495 2680);
DISPLAY 0.872340 (-1495 2680);
PAINT GREEN (-1495 2680);
DISPLAY INVISIBLE (-1495 2680);
FORCEPROP 1 LAST OFFPAGE TRUE
J 0
(-1125 2650);
DISPLAY 0.872340 (-1125 2650);
PAINT AQUA (-1125 2650);
DISPLAY INVISIBLE (-1125 2650);
FORCEPROP 2 LAST PATH I58
J 0
(-1250 2825);
DISPLAY 1.021277 (-1250 2825);
DISPLAY INVISIBLE (-1250 2825);
FORCEADD OFFPAGE..2
(-1450 2825);
FORCEPROP 2 LAST $XR0 166 
J 0
(-1261 2825);
DISPLAY 0.638298 (-1261 2825);
PAINT MONO (-1261 2825);
FORCEPROP 2 LAST CDS_LIB standard
J 0
(-1450 2825);
DISPLAY INVISIBLE (-1450 2825);
FORCEPROP 1 LAST COMMENT_BODY TRUE
J 0
(-1495 2730);
DISPLAY 0.872340 (-1495 2730);
PAINT GREEN (-1495 2730);
DISPLAY INVISIBLE (-1495 2730);
FORCEPROP 1 LAST OFFPAGE TRUE
J 0
(-1125 2700);
DISPLAY 0.872340 (-1125 2700);
PAINT AQUA (-1125 2700);
DISPLAY INVISIBLE (-1125 2700);
FORCEPROP 2 LAST PATH I59
J 0
(-1250 2875);
DISPLAY 1.021277 (-1250 2875);
DISPLAY INVISIBLE (-1250 2875);
FORCEADD OFFPAGE..2
(-475 -2150);
FORCEPROP 2 LAST $XR0 167 
J 0
(-286 -2150);
DISPLAY 0.638298 (-286 -2150);
PAINT MONO (-286 -2150);
FORCEPROP 1 LAST COMMENT_BODY TRUE
J 0
(-520 -2245);
DISPLAY 0.872340 (-520 -2245);
PAINT GREEN (-520 -2245);
DISPLAY INVISIBLE (-520 -2245);
FORCEPROP 1 LAST OFFPAGE TRUE
J 0
(-150 -2275);
DISPLAY 0.872340 (-150 -2275);
PAINT GREEN (-150 -2275);
DISPLAY INVISIBLE (-150 -2275);
FORCEPROP 2 LAST CDS_LIB standard
J 0
(-475 -2150);
DISPLAY INVISIBLE (-475 -2150);
FORCEPROP 2 LAST PATH I6
J 0
(-275 -2100);
DISPLAY 1.021277 (-275 -2100);
DISPLAY INVISIBLE (-275 -2100);
FORCEADD UNIVERSAL_GND..1
(375 -2875);
FORCEPROP 3 LASTPIN (375 -2825) SIG_NAME GND\g
J 0
(385 -2815);
DISPLAY 0.659574 (385 -2815);
PAINT MONO (385 -2815);
DISPLAY INVISIBLE (385 -2815);
FORCEPROP 2 LAST CDS_LIB logical_power
J 0
(375 -2875);
PAINT MONO (375 -2875);
DISPLAY INVISIBLE (375 -2875);
FORCEPROP 1 LAST HDL_POWER GND
J 1
(400 -2950);
DISPLAY 0.872340 (400 -2950);
PAINT GREEN (400 -2950);
DISPLAY INVISIBLE (400 -2950);
FORCEPROP 2 LAST ROOM IO_SLOT
J 1
(150 -2800);
DISPLAY 0.744681 (150 -2800);
DISPLAY INVISIBLE (150 -2800);
FORCEPROP 1 LAST PATH I60
J 0
(450 -2875);
DISPLAY 0.872340 (450 -2875);
PAINT AQUA (450 -2875);
DISPLAY INVISIBLE (450 -2875);
FORCEADD Q_RES..2
(375 -2650);
FORCEPROP 1 LAST PART_NUMBER CS21002FB06
J 0
(415 -2775);
DISPLAY 0.638298 (415 -2775);
DISPLAY INVISIBLE (415 -2775);
FORCEPROP 1 LAST VALUE 1K
J 0
(420 -2575);
DISPLAY 0.638298 (420 -2575);
FORCEPROP 1 LAST TOLERANCE 1%
J 0
(420 -2625);
DISPLAY 0.638298 (420 -2625);
FORCEPROP 1 LAST PACK_TYPE 0402LF
J 0
(415 -2825);
DISPLAY 0.638298 (415 -2825);
FORCEPROP 1 LAST MATERIAL EMPTY
J 0
(415 -2725);
DISPLAY 0.638298 (415 -2725);
PAINT RED (415 -2725);
FORCEPROP 1 LAST WATTAGE 1/16W
J 0
(415 -2675);
DISPLAY 0.638298 (415 -2675);
FORCEPROP 1 LAST $LOCATION R3381
J 0
(420 -2525);
DISPLAY 0.978723 (420 -2525);
FORCEPROP 1 LASTPIN (375 -2550) $PN 1
J 0
(380 -2588);
DISPLAY 0.787234 (380 -2588);
PAINT MONO (380 -2588);
FORCEPROP 1 LASTPIN (375 -2750) $PN 2
J 0
(380 -2740);
DISPLAY 0.787234 (380 -2740);
PAINT MONO (380 -2740);
FORCEPROP 2 LAST CDS_LIB pure_quanta
J 0
(375 -2650);
DISPLAY INVISIBLE (375 -2650);
FORCEPROP 1 LAST PATH I61
J 0
(425 -2475);
DISPLAY 0.978723 (425 -2475);
PAINT WHITE (425 -2475);
DISPLAY INVISIBLE (425 -2475);
FORCEPROP 0 LAST CDS_LOCATION R3381
J 0
(425 -2475);
DISPLAY 1.021277 (425 -2475);
DISPLAY INVISIBLE (425 -2475);
FORCEPROP 0 LAST $SEC 1
J 0
(425 -2475);
DISPLAY 0.680851 (425 -2475);
PAINT MONO (425 -2475);
DISPLAY INVISIBLE (425 -2475);
FORCEPROP 0 LAST CDS_SEC 1
J 0
(425 -2475);
DISPLAY 1.021277 (425 -2475);
DISPLAY INVISIBLE (425 -2475);
FORCEADD Q_RES..2
(375 -2125);
FORCEPROP 1 LAST PART_NUMBER CS21002FB06
J 0
(415 -2250);
DISPLAY 0.638298 (415 -2250);
DISPLAY INVISIBLE (415 -2250);
FORCEPROP 1 LAST PACK_TYPE 0402LF
J 0
(415 -2300);
DISPLAY 0.638298 (415 -2300);
FORCEPROP 1 LAST MATERIAL EMPTY
J 0
(415 -2200);
DISPLAY 0.638298 (415 -2200);
PAINT RED (415 -2200);
FORCEPROP 1 LAST TOLERANCE 1%
J 0
(420 -2100);
DISPLAY 0.638298 (420 -2100);
FORCEPROP 1 LAST WATTAGE 1/16W
J 0
(415 -2150);
DISPLAY 0.638298 (415 -2150);
FORCEPROP 1 LAST VALUE 1K
J 0
(420 -2050);
DISPLAY 0.638298 (420 -2050);
FORCEPROP 1 LAST $LOCATION R4655
J 0
(420 -2000);
DISPLAY 0.978723 (420 -2000);
FORCEPROP 1 LASTPIN (375 -2025) $PN 1
J 0
(380 -2063);
DISPLAY 0.787234 (380 -2063);
PAINT MONO (380 -2063);
FORCEPROP 1 LASTPIN (375 -2225) $PN 2
J 0
(380 -2215);
DISPLAY 0.787234 (380 -2215);
PAINT MONO (380 -2215);
FORCEPROP 2 LAST CDS_LIB pure_quanta
J 0
(375 -2125);
DISPLAY INVISIBLE (375 -2125);
FORCEPROP 1 LAST PATH I62
J 0
(425 -1950);
DISPLAY 0.978723 (425 -1950);
PAINT WHITE (425 -1950);
DISPLAY INVISIBLE (425 -1950);
FORCEPROP 0 LAST CDS_LOCATION R4655
J 0
(425 -1950);
DISPLAY 1.021277 (425 -1950);
DISPLAY INVISIBLE (425 -1950);
FORCEPROP 0 LAST $SEC 1
J 0
(425 -1950);
DISPLAY 0.680851 (425 -1950);
PAINT MONO (425 -1950);
DISPLAY INVISIBLE (425 -1950);
FORCEPROP 0 LAST CDS_SEC 1
J 0
(425 -1950);
DISPLAY 1.021277 (425 -1950);
DISPLAY INVISIBLE (425 -1950);
FORCEADD OFFPAGE..2
(1100 -2375);
FORCEPROP 2 LAST $XR0 167 
J 0
(1289 -2375);
DISPLAY 0.638298 (1289 -2375);
PAINT MONO (1289 -2375);
FORCEPROP 2 LAST CDS_LIB standard
J 0
(1100 -2375);
PAINT MONO (1100 -2375);
DISPLAY INVISIBLE (1100 -2375);
FORCEPROP 1 LAST OFFPAGE TRUE
J 0
(1425 -2500);
DISPLAY 0.872340 (1425 -2500);
PAINT GREEN (1425 -2500);
DISPLAY INVISIBLE (1425 -2500);
FORCEPROP 1 LAST COMMENT_BODY TRUE
J 0
(1055 -2470);
DISPLAY 0.872340 (1055 -2470);
PAINT GREEN (1055 -2470);
DISPLAY INVISIBLE (1055 -2470);
FORCEPROP 2 LAST PATH I63
J 0
(1300 -2325);
DISPLAY 1.021277 (1300 -2325);
DISPLAY INVISIBLE (1300 -2325);
FORCEADD UNIVERSAL_GND..1
(1575 -2900);
FORCEPROP 3 LASTPIN (1575 -2850) SIG_NAME GND\g
J 0
(1585 -2840);
DISPLAY 0.659574 (1585 -2840);
PAINT MONO (1585 -2840);
DISPLAY INVISIBLE (1585 -2840);
FORCEPROP 2 LAST ROOM IO_SLOT
J 1
(1350 -2825);
DISPLAY 0.744681 (1350 -2825);
DISPLAY INVISIBLE (1350 -2825);
FORCEPROP 1 LAST HDL_POWER GND
J 1
(1600 -2975);
DISPLAY 0.872340 (1600 -2975);
PAINT GREEN (1600 -2975);
DISPLAY INVISIBLE (1600 -2975);
FORCEPROP 2 LAST CDS_LIB logical_power
J 0
(1575 -2900);
PAINT MONO (1575 -2900);
DISPLAY INVISIBLE (1575 -2900);
FORCEPROP 1 LAST PATH I64
J 0
(1650 -2900);
DISPLAY 0.872340 (1650 -2900);
PAINT AQUA (1650 -2900);
DISPLAY INVISIBLE (1650 -2900);
FORCEADD Q_RES..2
(1575 -2675);
FORCEPROP 1 LAST PART_NUMBER CS21002FB06
J 0
(1615 -2800);
DISPLAY 0.638298 (1615 -2800);
DISPLAY INVISIBLE (1615 -2800);
FORCEPROP 1 LAST MATERIAL EMPTY
J 0
(1615 -2750);
DISPLAY 0.638298 (1615 -2750);
PAINT RED (1615 -2750);
FORCEPROP 1 LAST VALUE 1K
J 0
(1620 -2600);
DISPLAY 0.638298 (1620 -2600);
FORCEPROP 1 LAST PACK_TYPE 0402LF
J 0
(1615 -2850);
DISPLAY 0.638298 (1615 -2850);
FORCEPROP 1 LAST TOLERANCE 1%
J 0
(1620 -2650);
DISPLAY 0.638298 (1620 -2650);
FORCEPROP 1 LAST WATTAGE 1/16W
J 0
(1615 -2700);
DISPLAY 0.638298 (1615 -2700);
FORCEPROP 1 LAST $LOCATION R4657
J 0
(1620 -2550);
DISPLAY 0.978723 (1620 -2550);
FORCEPROP 1 LASTPIN (1575 -2575) $PN 1
J 0
(1580 -2613);
DISPLAY 0.787234 (1580 -2613);
PAINT MONO (1580 -2613);
FORCEPROP 1 LASTPIN (1575 -2775) $PN 2
J 0
(1580 -2765);
DISPLAY 0.787234 (1580 -2765);
PAINT MONO (1580 -2765);
FORCEPROP 2 LAST CDS_LIB pure_quanta
J 0
(1575 -2675);
DISPLAY INVISIBLE (1575 -2675);
FORCEPROP 1 LAST PATH I65
J 0
(1625 -2500);
DISPLAY 0.978723 (1625 -2500);
PAINT WHITE (1625 -2500);
DISPLAY INVISIBLE (1625 -2500);
FORCEPROP 0 LAST CDS_LOCATION R4657
J 0
(1625 -2500);
DISPLAY 1.021277 (1625 -2500);
DISPLAY INVISIBLE (1625 -2500);
FORCEPROP 0 LAST $SEC 1
J 0
(1625 -2500);
DISPLAY 0.680851 (1625 -2500);
PAINT MONO (1625 -2500);
DISPLAY INVISIBLE (1625 -2500);
FORCEPROP 0 LAST CDS_SEC 1
J 0
(1625 -2500);
DISPLAY 1.021277 (1625 -2500);
DISPLAY INVISIBLE (1625 -2500);
FORCEADD Q_RES..2
(1575 -2150);
FORCEPROP 1 LAST PART_NUMBER CS21002FB06
J 0
(1615 -2275);
DISPLAY 0.638298 (1615 -2275);
DISPLAY INVISIBLE (1615 -2275);
FORCEPROP 2 LAST ROOM PCIE REDRIVER1_BOM2
J 0
(1625 -1975);
DISPLAY 0.808511 (1625 -1975);
FORCEPROP 1 LAST PACK_TYPE 0402LF
J 0
(1615 -2325);
DISPLAY 0.638298 (1615 -2325);
FORCEPROP 1 LAST VALUE 1K
J 0
(1620 -2075);
DISPLAY 0.638298 (1620 -2075);
FORCEPROP 1 LAST MATERIAL CHIP
J 0
(1615 -2225);
DISPLAY 0.638298 (1615 -2225);
FORCEPROP 1 LAST TOLERANCE 1%
J 0
(1620 -2125);
DISPLAY 0.638298 (1620 -2125);
FORCEPROP 1 LAST WATTAGE 1/16W
J 0
(1615 -2175);
DISPLAY 0.638298 (1615 -2175);
FORCEPROP 1 LAST $LOCATION R4656
J 0
(1620 -2025);
DISPLAY 0.978723 (1620 -2025);
FORCEPROP 1 LASTPIN (1575 -2050) $PN 1
J 0
(1580 -2088);
DISPLAY 0.787234 (1580 -2088);
PAINT MONO (1580 -2088);
FORCEPROP 1 LASTPIN (1575 -2250) $PN 2
J 0
(1580 -2240);
DISPLAY 0.787234 (1580 -2240);
PAINT MONO (1580 -2240);
FORCEPROP 2 LAST CDS_LIB pure_quanta
J 0
(1575 -2150);
DISPLAY INVISIBLE (1575 -2150);
FORCEPROP 1 LAST PATH I66
J 0
(1625 -1975);
DISPLAY 0.978723 (1625 -1975);
PAINT WHITE (1625 -1975);
DISPLAY INVISIBLE (1625 -1975);
FORCEPROP 0 LAST CDS_LOCATION R4656
J 0
(1625 -1975);
DISPLAY 1.021277 (1625 -1975);
DISPLAY INVISIBLE (1625 -1975);
FORCEPROP 0 LAST $SEC 1
J 0
(1625 -1975);
DISPLAY 0.680851 (1625 -1975);
PAINT MONO (1625 -1975);
DISPLAY INVISIBLE (1625 -1975);
FORCEPROP 0 LAST CDS_SEC 1
J 0
(1625 -1975);
DISPLAY 1.021277 (1625 -1975);
DISPLAY INVISIBLE (1625 -1975);
FORCEADD Q_RES..2
(-50 -1025);
FORCEPROP 1 LAST PART_NUMBER CS21002FB06
J 0
(-10 -1150);
DISPLAY 0.638298 (-10 -1150);
DISPLAY INVISIBLE (-10 -1150);
FORCEPROP 1 LAST TOLERANCE 1%
J 0
(-5 -1000);
DISPLAY 0.638298 (-5 -1000);
FORCEPROP 1 LAST PACK_TYPE 0402LF
J 0
(-10 -1200);
DISPLAY 0.638298 (-10 -1200);
FORCEPROP 1 LAST MATERIAL CHIP
J 0
(-10 -1100);
DISPLAY 0.638298 (-10 -1100);
FORCEPROP 1 LAST WATTAGE 1/16W
J 0
(-10 -1050);
DISPLAY 0.638298 (-10 -1050);
FORCEPROP 1 LAST VALUE 1K
J 0
(-5 -950);
DISPLAY 0.638298 (-5 -950);
FORCEPROP 2 LAST ROOM PCIE REDRIVER1_BOM2
J 0
(0 -850);
DISPLAY 0.638298 (0 -850);
FORCEPROP 1 LAST $LOCATION R4654
J 0
(-5 -900);
DISPLAY 0.978723 (-5 -900);
FORCEPROP 1 LASTPIN (-50 -925) $PN 1
J 0
(-45 -963);
DISPLAY 0.787234 (-45 -963);
PAINT MONO (-45 -963);
FORCEPROP 1 LASTPIN (-50 -1125) $PN 2
J 0
(-45 -1115);
DISPLAY 0.787234 (-45 -1115);
PAINT MONO (-45 -1115);
FORCEPROP 2 LAST CDS_LIB pure_quanta
J 0
(-50 -1025);
DISPLAY INVISIBLE (-50 -1025);
FORCEPROP 1 LAST PATH I67
J 0
(0 -850);
DISPLAY 0.978723 (0 -850);
PAINT WHITE (0 -850);
DISPLAY INVISIBLE (0 -850);
FORCEPROP 0 LAST CDS_LOCATION R4654
J 0
(0 -850);
DISPLAY 1.021277 (0 -850);
DISPLAY INVISIBLE (0 -850);
FORCEPROP 0 LAST $SEC 1
J 0
(0 -850);
DISPLAY 0.680851 (0 -850);
PAINT MONO (0 -850);
DISPLAY INVISIBLE (0 -850);
FORCEPROP 0 LAST CDS_SEC 1
J 0
(0 -850);
DISPLAY 1.021277 (0 -850);
DISPLAY INVISIBLE (0 -850);
FORCEADD UNIVERSAL_GND..1
(-50 -1350);
FORCEPROP 3 LASTPIN (-50 -1300) SIG_NAME GND\g
J 0
(-40 -1290);
DISPLAY 0.659574 (-40 -1290);
PAINT MONO (-40 -1290);
DISPLAY INVISIBLE (-40 -1290);
FORCEPROP 2 LAST ROOM IO_SLOT
J 1
(-275 -1275);
DISPLAY 0.744681 (-275 -1275);
DISPLAY INVISIBLE (-275 -1275);
FORCEPROP 1 LAST HDL_POWER GND
J 1
(-25 -1425);
DISPLAY 0.872340 (-25 -1425);
PAINT GREEN (-25 -1425);
DISPLAY INVISIBLE (-25 -1425);
FORCEPROP 2 LAST CDS_LIB logical_power
J 0
(-50 -1350);
DISPLAY INVISIBLE (-50 -1350);
FORCEPROP 1 LAST PATH I68
J 0
(25 -1350);
DISPLAY 0.872340 (25 -1350);
PAINT AQUA (25 -1350);
DISPLAY INVISIBLE (25 -1350);
FORCEADD UNIVERSAL_POWER..1
(375 -1825);
FORCEPROP 3 LASTPIN (375 -1875) SIG_NAME P3V3_AUX\g
J 0
(385 -1865);
DISPLAY 0.659574 (385 -1865);
PAINT MONO (385 -1865);
DISPLAY INVISIBLE (385 -1865);
FORCEPROP 1 LAST HDL_POWER P3V3_AUX
J 1
(375 -1775);
DISPLAY 0.872340 (375 -1775);
PAINT GREEN (375 -1775);
FORCEPROP 2 LAST CDS_LIB logical_power
J 0
(375 -1825);
PAINT MONO (375 -1825);
DISPLAY INVISIBLE (375 -1825);
FORCEPROP 1 LAST PATH I69
J 0
(425 -1800);
DISPLAY 0.872340 (425 -1800);
PAINT AQUA (425 -1800);
DISPLAY INVISIBLE (425 -1800);
FORCEADD Q_RES..2
(-1550 -1925);
FORCEPROP 1 LAST PART_NUMBER CS21002FB06
J 0
(-1510 -2050);
DISPLAY 0.638298 (-1510 -2050);
DISPLAY INVISIBLE (-1510 -2050);
FORCEPROP 1 LAST TOLERANCE 1%
J 0
(-1505 -1900);
DISPLAY 0.638298 (-1505 -1900);
FORCEPROP 1 LAST VALUE 1K
J 0
(-1505 -1850);
DISPLAY 0.638298 (-1505 -1850);
FORCEPROP 1 LAST WATTAGE 1/16W
J 0
(-1510 -1950);
DISPLAY 0.638298 (-1510 -1950);
FORCEPROP 1 LAST MATERIAL EMPTY
J 0
(-1510 -2000);
DISPLAY 0.638298 (-1510 -2000);
PAINT RED (-1510 -2000);
FORCEPROP 1 LAST PACK_TYPE 0402LF
J 0
(-1510 -2100);
DISPLAY 0.638298 (-1510 -2100);
FORCEPROP 1 LAST $LOCATION R4642
J 0
(-1505 -1800);
DISPLAY 0.638298 (-1505 -1800);
FORCEPROP 1 LASTPIN (-1550 -1825) $PN 1
J 0
(-1545 -1863);
DISPLAY 0.787234 (-1545 -1863);
PAINT MONO (-1545 -1863);
FORCEPROP 1 LASTPIN (-1550 -2025) $PN 2
J 0
(-1545 -2015);
DISPLAY 0.787234 (-1545 -2015);
PAINT MONO (-1545 -2015);
FORCEPROP 2 LAST CDS_LIB pure_quanta
J 0
(-1550 -1925);
DISPLAY INVISIBLE (-1550 -1925);
FORCEPROP 1 LAST PATH I7
J 0
(-1500 -1750);
DISPLAY 0.978723 (-1500 -1750);
PAINT WHITE (-1500 -1750);
DISPLAY INVISIBLE (-1500 -1750);
FORCEPROP 0 LAST CDS_LOCATION R4642
J 0
(-1500 -1750);
DISPLAY 1.021277 (-1500 -1750);
DISPLAY INVISIBLE (-1500 -1750);
FORCEPROP 0 LAST $SEC 1
J 0
(-1500 -1750);
DISPLAY 0.680851 (-1500 -1750);
PAINT MONO (-1500 -1750);
DISPLAY INVISIBLE (-1500 -1750);
FORCEPROP 0 LAST CDS_SEC 1
J 0
(-1500 -1750);
DISPLAY 1.021277 (-1500 -1750);
DISPLAY INVISIBLE (-1500 -1750);
FORCEADD UNIVERSAL_GND..1
(375 -1350);
FORCEPROP 3 LASTPIN (375 -1300) SIG_NAME GND\g
J 0
(385 -1290);
DISPLAY 0.659574 (385 -1290);
PAINT MONO (385 -1290);
DISPLAY INVISIBLE (385 -1290);
FORCEPROP 2 LAST CDS_LIB logical_power
J 0
(375 -1350);
DISPLAY INVISIBLE (375 -1350);
FORCEPROP 1 LAST HDL_POWER GND
J 1
(400 -1425);
DISPLAY 0.872340 (400 -1425);
PAINT GREEN (400 -1425);
DISPLAY INVISIBLE (400 -1425);
FORCEPROP 2 LAST ROOM IO_SLOT
J 1
(150 -1275);
DISPLAY 0.744681 (150 -1275);
DISPLAY INVISIBLE (150 -1275);
FORCEPROP 1 LAST PATH I70
J 0
(450 -1350);
DISPLAY 0.872340 (450 -1350);
PAINT AQUA (450 -1350);
DISPLAY INVISIBLE (450 -1350);
FORCEADD Q_RES..2
(375 -1025);
FORCEPROP 1 LAST PART_NUMBER CS21002FB06
J 0
(415 -1150);
DISPLAY 0.638298 (415 -1150);
DISPLAY INVISIBLE (415 -1150);
FORCEPROP 1 LAST PACK_TYPE 0402LF
J 0
(415 -1200);
DISPLAY 0.638298 (415 -1200);
FORCEPROP 1 LAST VALUE 1K
J 0
(420 -950);
DISPLAY 0.638298 (420 -950);
FORCEPROP 1 LAST MATERIAL EMPTY
J 0
(415 -1100);
DISPLAY 0.638298 (415 -1100);
PAINT RED (415 -1100);
FORCEPROP 1 LAST WATTAGE 1/16W
J 0
(415 -1050);
DISPLAY 0.638298 (415 -1050);
FORCEPROP 1 LAST TOLERANCE 1%
J 0
(420 -1000);
DISPLAY 0.638298 (420 -1000);
FORCEPROP 1 LAST $LOCATION R4650
J 0
(420 -900);
DISPLAY 0.978723 (420 -900);
FORCEPROP 1 LASTPIN (375 -925) $PN 1
J 0
(380 -963);
DISPLAY 0.787234 (380 -963);
PAINT MONO (380 -963);
FORCEPROP 1 LASTPIN (375 -1125) $PN 2
J 0
(380 -1115);
DISPLAY 0.787234 (380 -1115);
PAINT MONO (380 -1115);
FORCEPROP 2 LAST CDS_LIB pure_quanta
J 0
(375 -1025);
DISPLAY INVISIBLE (375 -1025);
FORCEPROP 1 LAST PATH I71
J 0
(425 -850);
DISPLAY 0.978723 (425 -850);
PAINT WHITE (425 -850);
DISPLAY INVISIBLE (425 -850);
FORCEPROP 0 LAST CDS_LOCATION R4650
J 0
(425 -850);
DISPLAY 1.021277 (425 -850);
DISPLAY INVISIBLE (425 -850);
FORCEPROP 0 LAST $SEC 1
J 0
(425 -850);
DISPLAY 0.680851 (425 -850);
PAINT MONO (425 -850);
DISPLAY INVISIBLE (425 -850);
FORCEPROP 0 LAST CDS_SEC 1
J 0
(425 -850);
DISPLAY 1.021277 (425 -850);
DISPLAY INVISIBLE (425 -850);
FORCEADD Q_RES..2
(-50 -475);
FORCEPROP 1 LAST PART_NUMBER CS21002FB06
J 0
(-10 -600);
DISPLAY 0.638298 (-10 -600);
DISPLAY INVISIBLE (-10 -600);
FORCEPROP 1 LAST WATTAGE 1/16W
J 0
(-10 -500);
DISPLAY 0.638298 (-10 -500);
FORCEPROP 1 LAST VALUE 1K
J 0
(-5 -400);
DISPLAY 0.638298 (-5 -400);
FORCEPROP 1 LAST TOLERANCE 1%
J 0
(-5 -450);
DISPLAY 0.638298 (-5 -450);
FORCEPROP 1 LAST PACK_TYPE 0402LF
J 0
(-10 -650);
DISPLAY 0.638298 (-10 -650);
FORCEPROP 1 LAST MATERIAL EMPTY
J 0
(-10 -550);
DISPLAY 0.638298 (-10 -550);
PAINT RED (-10 -550);
FORCEPROP 1 LAST $LOCATION R4648
J 0
(-5 -350);
DISPLAY 0.638298 (-5 -350);
FORCEPROP 1 LASTPIN (-50 -375) $PN 1
J 0
(-45 -413);
DISPLAY 0.787234 (-45 -413);
PAINT MONO (-45 -413);
FORCEPROP 1 LASTPIN (-50 -575) $PN 2
J 0
(-45 -565);
DISPLAY 0.787234 (-45 -565);
PAINT MONO (-45 -565);
FORCEPROP 2 LAST CDS_LIB pure_quanta
J 0
(-50 -475);
DISPLAY INVISIBLE (-50 -475);
FORCEPROP 1 LAST PATH I72
J 0
(0 -300);
DISPLAY 0.978723 (0 -300);
PAINT WHITE (0 -300);
DISPLAY INVISIBLE (0 -300);
FORCEPROP 0 LAST CDS_LOCATION R4648
J 0
(0 -300);
DISPLAY 1.021277 (0 -300);
DISPLAY INVISIBLE (0 -300);
FORCEPROP 0 LAST $SEC 1
J 0
(0 -300);
DISPLAY 0.680851 (0 -300);
PAINT MONO (0 -300);
DISPLAY INVISIBLE (0 -300);
FORCEPROP 0 LAST CDS_SEC 1
J 0
(0 -300);
DISPLAY 1.021277 (0 -300);
DISPLAY INVISIBLE (0 -300);
FORCEADD UNIVERSAL_POWER..1
(-50 -175);
FORCEPROP 3 LASTPIN (-50 -225) SIG_NAME P3V3_AUX\g
J 0
(-40 -215);
DISPLAY 0.659574 (-40 -215);
PAINT MONO (-40 -215);
DISPLAY INVISIBLE (-40 -215);
FORCEPROP 1 LAST HDL_POWER P3V3_AUX
J 1
(-50 -125);
DISPLAY 0.872340 (-50 -125);
PAINT GREEN (-50 -125);
FORCEPROP 2 LAST CDS_LIB logical_power
J 0
(-50 -175);
DISPLAY INVISIBLE (-50 -175);
FORCEPROP 1 LAST PATH I73
J 0
(0 -150);
DISPLAY 0.872340 (0 -150);
PAINT AQUA (0 -150);
DISPLAY INVISIBLE (0 -150);
FORCEADD Q_RES..2
(375 -475);
FORCEPROP 1 LAST PART_NUMBER CS21002FB06
J 0
(415 -600);
DISPLAY 0.638298 (415 -600);
DISPLAY INVISIBLE (415 -600);
FORCEPROP 1 LAST WATTAGE 1/16W
J 0
(415 -500);
DISPLAY 0.638298 (415 -500);
FORCEPROP 1 LAST VALUE 1K
J 0
(420 -400);
DISPLAY 0.638298 (420 -400);
FORCEPROP 1 LAST TOLERANCE 1%
J 0
(420 -450);
DISPLAY 0.638298 (420 -450);
FORCEPROP 1 LAST PACK_TYPE 0402LF
J 0
(415 -650);
DISPLAY 0.638298 (415 -650);
FORCEPROP 1 LAST MATERIAL EMPTY
J 0
(415 -550);
DISPLAY 0.638298 (415 -550);
PAINT RED (415 -550);
FORCEPROP 1 LAST $LOCATION R4649
J 0
(420 -350);
DISPLAY 0.978723 (420 -350);
FORCEPROP 1 LASTPIN (375 -375) $PN 1
J 0
(380 -413);
DISPLAY 0.787234 (380 -413);
PAINT MONO (380 -413);
FORCEPROP 1 LASTPIN (375 -575) $PN 2
J 0
(380 -565);
DISPLAY 0.787234 (380 -565);
PAINT MONO (380 -565);
FORCEPROP 2 LAST CDS_LIB pure_quanta
J 0
(375 -475);
DISPLAY INVISIBLE (375 -475);
FORCEPROP 1 LAST PATH I74
J 0
(425 -300);
DISPLAY 0.978723 (425 -300);
PAINT WHITE (425 -300);
DISPLAY INVISIBLE (425 -300);
FORCEPROP 0 LAST CDS_LOCATION R4649
J 0
(425 -300);
DISPLAY 1.021277 (425 -300);
DISPLAY INVISIBLE (425 -300);
FORCEPROP 0 LAST $SEC 1
J 0
(425 -300);
DISPLAY 0.680851 (425 -300);
PAINT MONO (425 -300);
DISPLAY INVISIBLE (425 -300);
FORCEPROP 0 LAST CDS_SEC 1
J 0
(425 -300);
DISPLAY 1.021277 (425 -300);
DISPLAY INVISIBLE (425 -300);
FORCEADD UNIVERSAL_POWER..1
(1575 -1850);
FORCEPROP 3 LASTPIN (1575 -1900) SIG_NAME P3V3_AUX\g
J 0
(1585 -1890);
DISPLAY 0.659574 (1585 -1890);
PAINT MONO (1585 -1890);
DISPLAY INVISIBLE (1585 -1890);
FORCEPROP 1 LAST HDL_POWER P3V3_AUX
J 1
(1575 -1800);
DISPLAY 0.872340 (1575 -1800);
PAINT GREEN (1575 -1800);
FORCEPROP 2 LAST CDS_LIB logical_power
J 0
(1575 -1850);
PAINT MONO (1575 -1850);
DISPLAY INVISIBLE (1575 -1850);
FORCEPROP 1 LAST PATH I75
J 0
(1625 -1825);
DISPLAY 0.872340 (1625 -1825);
PAINT AQUA (1625 -1825);
DISPLAY INVISIBLE (1625 -1825);
FORCEADD OFFPAGE..2
(1025 -750);
FORCEPROP 2 LAST $XR0 167 
J 0
(1214 -750);
DISPLAY 0.638298 (1214 -750);
PAINT MONO (1214 -750);
FORCEPROP 2 LAST CDS_LIB standard
J 0
(1025 -750);
DISPLAY INVISIBLE (1025 -750);
FORCEPROP 1 LAST OFFPAGE TRUE
J 0
(1350 -875);
DISPLAY 0.872340 (1350 -875);
PAINT GREEN (1350 -875);
DISPLAY INVISIBLE (1350 -875);
FORCEPROP 1 LAST COMMENT_BODY TRUE
J 0
(980 -845);
DISPLAY 0.872340 (980 -845);
PAINT GREEN (980 -845);
DISPLAY INVISIBLE (980 -845);
FORCEPROP 2 LAST PATH I76
J 0
(1225 -700);
DISPLAY 1.021277 (1225 -700);
DISPLAY INVISIBLE (1225 -700);
FORCEADD OFFPAGE..2
(1025 -700);
FORCEPROP 2 LAST $XR0 167 
J 0
(1214 -700);
DISPLAY 0.638298 (1214 -700);
PAINT MONO (1214 -700);
FORCEPROP 2 LAST CDS_LIB standard
J 0
(1025 -700);
DISPLAY INVISIBLE (1025 -700);
FORCEPROP 1 LAST OFFPAGE TRUE
J 0
(1350 -825);
DISPLAY 0.872340 (1350 -825);
PAINT GREEN (1350 -825);
DISPLAY INVISIBLE (1350 -825);
FORCEPROP 1 LAST COMMENT_BODY TRUE
J 0
(980 -795);
DISPLAY 0.872340 (980 -795);
PAINT GREEN (980 -795);
DISPLAY INVISIBLE (980 -795);
FORCEPROP 2 LAST PATH I77
J 0
(1225 -650);
DISPLAY 1.021277 (1225 -650);
DISPLAY INVISIBLE (1225 -650);
FORCEADD OFFPAGE..2
(2300 -2400);
FORCEPROP 2 LAST $XR0 167 
J 0
(2489 -2400);
DISPLAY 0.638298 (2489 -2400);
PAINT MONO (2489 -2400);
FORCEPROP 1 LAST COMMENT_BODY TRUE
J 0
(2255 -2495);
DISPLAY 0.872340 (2255 -2495);
PAINT GREEN (2255 -2495);
DISPLAY INVISIBLE (2255 -2495);
FORCEPROP 1 LAST OFFPAGE TRUE
J 0
(2625 -2525);
DISPLAY 0.872340 (2625 -2525);
PAINT GREEN (2625 -2525);
DISPLAY INVISIBLE (2625 -2525);
FORCEPROP 2 LAST CDS_LIB standard
J 0
(2300 -2400);
PAINT MONO (2300 -2400);
DISPLAY INVISIBLE (2300 -2400);
FORCEPROP 2 LAST PATH I78
J 0
(2500 -2350);
DISPLAY 1.021277 (2500 -2350);
DISPLAY INVISIBLE (2500 -2350);
FORCEADD UNIVERSAL_GND..1
(2750 -2875);
FORCEPROP 3 LASTPIN (2750 -2825) SIG_NAME GND\g
J 0
(2760 -2815);
DISPLAY 0.659574 (2760 -2815);
PAINT MONO (2760 -2815);
DISPLAY INVISIBLE (2760 -2815);
FORCEPROP 2 LAST ROOM IO_SLOT
J 1
(2525 -2800);
DISPLAY 0.744681 (2525 -2800);
DISPLAY INVISIBLE (2525 -2800);
FORCEPROP 1 LAST HDL_POWER GND
J 1
(2775 -2950);
DISPLAY 0.872340 (2775 -2950);
PAINT GREEN (2775 -2950);
DISPLAY INVISIBLE (2775 -2950);
FORCEPROP 2 LAST CDS_LIB logical_power
J 0
(2750 -2875);
PAINT MONO (2750 -2875);
DISPLAY INVISIBLE (2750 -2875);
FORCEPROP 1 LAST PATH I79
J 0
(2825 -2875);
DISPLAY 0.872340 (2825 -2875);
PAINT AQUA (2825 -2875);
DISPLAY INVISIBLE (2825 -2875);
FORCEADD UNIVERSAL_POWER..1
(-1550 -1625);
FORCEPROP 3 LASTPIN (-1550 -1675) SIG_NAME P3V3_AUX\g
J 0
(-1540 -1665);
DISPLAY 0.659574 (-1540 -1665);
PAINT MONO (-1540 -1665);
DISPLAY INVISIBLE (-1540 -1665);
FORCEPROP 1 LAST HDL_POWER P3V3_AUX
J 1
(-1550 -1575);
DISPLAY 0.872340 (-1550 -1575);
PAINT GREEN (-1550 -1575);
FORCEPROP 2 LAST CDS_LIB logical_power
J 0
(-1550 -1625);
DISPLAY INVISIBLE (-1550 -1625);
FORCEPROP 1 LAST PATH I8
J 0
(-1500 -1600);
DISPLAY 0.872340 (-1500 -1600);
PAINT AQUA (-1500 -1600);
DISPLAY INVISIBLE (-1500 -1600);
FORCEADD Q_RES..2
(2750 -2650);
FORCEPROP 1 LAST PART_NUMBER CS21002FB06
J 0
(2790 -2775);
DISPLAY 0.638298 (2790 -2775);
DISPLAY INVISIBLE (2790 -2775);
FORCEPROP 1 LAST MATERIAL EMPTY
J 0
(2790 -2725);
DISPLAY 0.638298 (2790 -2725);
PAINT RED (2790 -2725);
FORCEPROP 1 LAST VALUE 1K
J 0
(2795 -2575);
DISPLAY 0.638298 (2795 -2575);
FORCEPROP 1 LAST PACK_TYPE 0402LF
J 0
(2790 -2825);
DISPLAY 0.638298 (2790 -2825);
FORCEPROP 1 LAST TOLERANCE 1%
J 0
(2795 -2625);
DISPLAY 0.638298 (2795 -2625);
FORCEPROP 1 LAST WATTAGE 1/16W
J 0
(2790 -2675);
DISPLAY 0.638298 (2790 -2675);
FORCEPROP 1 LAST $LOCATION R4658
J 0
(2795 -2525);
DISPLAY 0.978723 (2795 -2525);
FORCEPROP 1 LASTPIN (2750 -2550) $PN 1
J 0
(2755 -2588);
DISPLAY 0.787234 (2755 -2588);
PAINT MONO (2755 -2588);
FORCEPROP 1 LASTPIN (2750 -2750) $PN 2
J 0
(2755 -2740);
DISPLAY 0.787234 (2755 -2740);
PAINT MONO (2755 -2740);
FORCEPROP 2 LAST CDS_LIB pure_quanta
J 0
(2750 -2650);
DISPLAY INVISIBLE (2750 -2650);
FORCEPROP 1 LAST PATH I80
J 0
(2800 -2475);
DISPLAY 0.978723 (2800 -2475);
PAINT WHITE (2800 -2475);
DISPLAY INVISIBLE (2800 -2475);
FORCEPROP 0 LAST CDS_LOCATION R4658
J 0
(2800 -2475);
DISPLAY 1.021277 (2800 -2475);
DISPLAY INVISIBLE (2800 -2475);
FORCEPROP 0 LAST $SEC 1
J 0
(2800 -2475);
DISPLAY 0.680851 (2800 -2475);
PAINT MONO (2800 -2475);
DISPLAY INVISIBLE (2800 -2475);
FORCEPROP 0 LAST CDS_SEC 1
J 0
(2800 -2475);
DISPLAY 1.021277 (2800 -2475);
DISPLAY INVISIBLE (2800 -2475);
FORCEADD Q_RES..2
(2750 -2125);
FORCEPROP 1 LAST PART_NUMBER CS21002FB06
J 0
(2790 -2250);
DISPLAY 0.638298 (2790 -2250);
DISPLAY INVISIBLE (2790 -2250);
FORCEPROP 2 LAST ROOM PCIE REDRIVER1_BOM2
J 0
(2800 -1950);
DISPLAY 0.808511 (2800 -1950);
FORCEPROP 1 LAST MATERIAL CHIP
J 0
(2790 -2200);
DISPLAY 0.638298 (2790 -2200);
FORCEPROP 1 LAST PACK_TYPE 0402LF
J 0
(2790 -2300);
DISPLAY 0.638298 (2790 -2300);
FORCEPROP 1 LAST VALUE 1K
J 0
(2795 -2050);
DISPLAY 0.638298 (2795 -2050);
FORCEPROP 1 LAST TOLERANCE 1%
J 0
(2795 -2100);
DISPLAY 0.638298 (2795 -2100);
FORCEPROP 1 LAST WATTAGE 1/16W
J 0
(2790 -2150);
DISPLAY 0.638298 (2790 -2150);
FORCEPROP 1 LAST $LOCATION R3386
J 0
(2795 -2000);
DISPLAY 0.978723 (2795 -2000);
FORCEPROP 1 LASTPIN (2750 -2025) $PN 1
J 0
(2755 -2063);
DISPLAY 0.787234 (2755 -2063);
PAINT MONO (2755 -2063);
FORCEPROP 1 LASTPIN (2750 -2225) $PN 2
J 0
(2755 -2215);
DISPLAY 0.787234 (2755 -2215);
PAINT MONO (2755 -2215);
FORCEPROP 2 LAST CDS_LIB pure_quanta
J 0
(2750 -2125);
DISPLAY INVISIBLE (2750 -2125);
FORCEPROP 1 LAST PATH I81
J 0
(2800 -1950);
DISPLAY 0.978723 (2800 -1950);
PAINT WHITE (2800 -1950);
DISPLAY INVISIBLE (2800 -1950);
FORCEPROP 0 LAST CDS_LOCATION R3386
J 0
(2800 -1950);
DISPLAY 1.021277 (2800 -1950);
DISPLAY INVISIBLE (2800 -1950);
FORCEPROP 0 LAST $SEC 1
J 0
(2800 -1950);
DISPLAY 0.680851 (2800 -1950);
PAINT MONO (2800 -1950);
DISPLAY INVISIBLE (2800 -1950);
FORCEPROP 0 LAST CDS_SEC 1
J 0
(2800 -1950);
DISPLAY 1.021277 (2800 -1950);
DISPLAY INVISIBLE (2800 -1950);
FORCEADD OFFPAGE..2
(3475 -2375);
FORCEPROP 2 LAST $XR0 167 
J 0
(3664 -2375);
DISPLAY 0.638298 (3664 -2375);
PAINT MONO (3664 -2375);
FORCEPROP 2 LAST CDS_LIB standard
J 0
(3475 -2375);
PAINT MONO (3475 -2375);
DISPLAY INVISIBLE (3475 -2375);
FORCEPROP 1 LAST OFFPAGE TRUE
J 0
(3800 -2500);
DISPLAY 0.872340 (3800 -2500);
PAINT GREEN (3800 -2500);
DISPLAY INVISIBLE (3800 -2500);
FORCEPROP 1 LAST COMMENT_BODY TRUE
J 0
(3430 -2470);
DISPLAY 0.872340 (3430 -2470);
PAINT GREEN (3430 -2470);
DISPLAY INVISIBLE (3430 -2470);
FORCEPROP 2 LAST PATH I82
J 0
(3675 -2325);
DISPLAY 1.021277 (3675 -2325);
DISPLAY INVISIBLE (3675 -2325);
FORCEADD UNIVERSAL_POWER..1
(2750 -1825);
FORCEPROP 3 LASTPIN (2750 -1875) SIG_NAME P3V3_AUX\g
J 0
(2760 -1865);
DISPLAY 0.659574 (2760 -1865);
PAINT MONO (2760 -1865);
DISPLAY INVISIBLE (2760 -1865);
FORCEPROP 1 LAST HDL_POWER P3V3_AUX
J 1
(2750 -1775);
DISPLAY 0.872340 (2750 -1775);
PAINT GREEN (2750 -1775);
FORCEPROP 2 LAST CDS_LIB logical_power
J 0
(2750 -1825);
PAINT MONO (2750 -1825);
DISPLAY INVISIBLE (2750 -1825);
FORCEPROP 1 LAST PATH I83
J 0
(2800 -1800);
DISPLAY 0.872340 (2800 -1800);
PAINT AQUA (2800 -1800);
DISPLAY INVISIBLE (2800 -1800);
FORCEADD OFFPAGE..4
R 2
(-75 1000);
FORCEPROP 2 LAST $XR0 167 
J 0
(-327 1000);
DISPLAY 0.638298 (-327 1000);
PAINT MONO (-327 1000);
FORCEPROP 1 LAST COMMENT_BODY TRUE
J 2
(-50 900);
DISPLAY 0.872340 (-50 900);
PAINT GREEN (-50 900);
DISPLAY INVISIBLE (-50 900);
FORCEPROP 1 LAST OFFPAGE TRUE
J 2
(-400 875);
DISPLAY 0.872340 (-400 875);
PAINT GREEN (-400 875);
DISPLAY INVISIBLE (-400 875);
FORCEPROP 2 LAST CDS_LIB standard
J 2
(-75 1000);
DISPLAY INVISIBLE (-75 1000);
FORCEPROP 2 LAST PATH I84
J 0
(-325 1050);
DISPLAY 1.021277 (-325 1050);
DISPLAY INVISIBLE (-325 1050);
FORCEADD OFFPAGE..4
R 2
(-75 1050);
FORCEPROP 2 LAST $XR0 167 
J 0
(-327 1050);
DISPLAY 0.638298 (-327 1050);
PAINT MONO (-327 1050);
FORCEPROP 1 LAST COMMENT_BODY TRUE
J 2
(-50 950);
DISPLAY 0.872340 (-50 950);
PAINT GREEN (-50 950);
DISPLAY INVISIBLE (-50 950);
FORCEPROP 1 LAST OFFPAGE TRUE
J 2
(-400 925);
DISPLAY 0.872340 (-400 925);
PAINT GREEN (-400 925);
DISPLAY INVISIBLE (-400 925);
FORCEPROP 2 LAST CDS_LIB standard
J 0
(-75 1050);
DISPLAY INVISIBLE (-75 1050);
FORCEPROP 2 LAST PATH I85
J 0
(-325 1100);
DISPLAY 1.021277 (-325 1100);
DISPLAY INVISIBLE (-325 1100);
FORCEADD OFFPAGE..4
R 2
(-50 1150);
FORCEPROP 2 LAST $XR0 167 
J 0
(-302 1150);
DISPLAY 0.638298 (-302 1150);
PAINT MONO (-302 1150);
FORCEPROP 2 LAST CDS_LIB standard
J 0
(-50 1150);
DISPLAY INVISIBLE (-50 1150);
FORCEPROP 1 LAST OFFPAGE TRUE
J 2
(-375 1025);
DISPLAY 0.872340 (-375 1025);
PAINT GREEN (-375 1025);
DISPLAY INVISIBLE (-375 1025);
FORCEPROP 1 LAST COMMENT_BODY TRUE
J 2
(-25 1050);
DISPLAY 0.872340 (-25 1050);
PAINT GREEN (-25 1050);
DISPLAY INVISIBLE (-25 1050);
FORCEPROP 2 LAST PATH I86
J 0
(-300 1200);
DISPLAY 1.021277 (-300 1200);
DISPLAY INVISIBLE (-300 1200);
FORCEADD OFFPAGE..4
R 2
(-50 1200);
FORCEPROP 2 LAST $XR0 167 
J 0
(-302 1200);
DISPLAY 0.638298 (-302 1200);
PAINT MONO (-302 1200);
FORCEPROP 2 LAST CDS_LIB standard
J 0
(-50 1200);
DISPLAY INVISIBLE (-50 1200);
FORCEPROP 1 LAST OFFPAGE TRUE
J 2
(-375 1075);
DISPLAY 0.872340 (-375 1075);
PAINT GREEN (-375 1075);
DISPLAY INVISIBLE (-375 1075);
FORCEPROP 1 LAST COMMENT_BODY TRUE
J 2
(-25 1100);
DISPLAY 0.872340 (-25 1100);
PAINT GREEN (-25 1100);
DISPLAY INVISIBLE (-25 1100);
FORCEPROP 2 LAST PATH I87
J 0
(-300 1250);
DISPLAY 1.021277 (-300 1250);
DISPLAY INVISIBLE (-300 1250);
FORCEADD OFFPAGE..4
R 2
(-50 1300);
FORCEPROP 2 LAST $XR0 167 
J 0
(-476 1300);
DISPLAY 0.638298 (-476 1300);
PAINT MONO (-476 1300);
FORCEPROP 1 LAST COMMENT_BODY TRUE
J 2
(-25 1200);
DISPLAY 0.872340 (-25 1200);
PAINT GREEN (-25 1200);
DISPLAY INVISIBLE (-25 1200);
FORCEPROP 1 LAST OFFPAGE TRUE
J 2
(-375 1175);
DISPLAY 0.872340 (-375 1175);
PAINT GREEN (-375 1175);
DISPLAY INVISIBLE (-375 1175);
FORCEPROP 2 LAST CDS_LIB standard
J 0
(-50 1300);
DISPLAY INVISIBLE (-50 1300);
FORCEPROP 2 LAST PATH I88
J 0
(-300 1350);
DISPLAY 1.021277 (-300 1350);
DISPLAY INVISIBLE (-300 1350);
FORCEADD OFFPAGE..4
R 2
(-50 1350);
FORCEPROP 2 LAST $XR0 167 
J 0
(-476 1350);
DISPLAY 0.638298 (-476 1350);
PAINT MONO (-476 1350);
FORCEPROP 1 LAST COMMENT_BODY TRUE
J 2
(-25 1250);
DISPLAY 0.872340 (-25 1250);
PAINT GREEN (-25 1250);
DISPLAY INVISIBLE (-25 1250);
FORCEPROP 1 LAST OFFPAGE TRUE
J 2
(-375 1225);
DISPLAY 0.872340 (-375 1225);
PAINT GREEN (-375 1225);
DISPLAY INVISIBLE (-375 1225);
FORCEPROP 2 LAST CDS_LIB standard
J 0
(-50 1350);
DISPLAY INVISIBLE (-50 1350);
FORCEPROP 2 LAST PATH I89
J 0
(-300 1400);
DISPLAY 1.021277 (-300 1400);
DISPLAY INVISIBLE (-300 1400);
FORCEADD UNIVERSAL_GND..1
(-1550 -1325);
FORCEPROP 3 LASTPIN (-1550 -1275) SIG_NAME GND\g
J 0
(-1540 -1265);
DISPLAY 0.659574 (-1540 -1265);
PAINT MONO (-1540 -1265);
DISPLAY INVISIBLE (-1540 -1265);
FORCEPROP 2 LAST ROOM IO_SLOT
J 1
(-1775 -1250);
DISPLAY 0.744681 (-1775 -1250);
DISPLAY INVISIBLE (-1775 -1250);
FORCEPROP 1 LAST HDL_POWER GND
J 1
(-1525 -1400);
DISPLAY 0.872340 (-1525 -1400);
PAINT GREEN (-1525 -1400);
DISPLAY INVISIBLE (-1525 -1400);
FORCEPROP 2 LAST CDS_LIB logical_power
J 0
(-1550 -1325);
DISPLAY INVISIBLE (-1550 -1325);
FORCEPROP 1 LAST PATH I9
J 0
(-1475 -1325);
DISPLAY 0.872340 (-1475 -1325);
PAINT AQUA (-1475 -1325);
DISPLAY INVISIBLE (-1475 -1325);
FORCEADD OFFPAGE..4
R 2
(-50 1700);
FORCEPROP 2 LAST $XR0 167 
J 0
(-302 1700);
DISPLAY 0.638298 (-302 1700);
PAINT MONO (-302 1700);
FORCEPROP 1 LAST COMMENT_BODY TRUE
J 2
(-25 1600);
DISPLAY 0.872340 (-25 1600);
PAINT GREEN (-25 1600);
DISPLAY INVISIBLE (-25 1600);
FORCEPROP 1 LAST OFFPAGE TRUE
J 2
(-375 1575);
DISPLAY 0.872340 (-375 1575);
PAINT GREEN (-375 1575);
DISPLAY INVISIBLE (-375 1575);
FORCEPROP 2 LAST CDS_LIB standard
J 0
(-50 1700);
DISPLAY INVISIBLE (-50 1700);
FORCEPROP 2 LAST PATH I90
J 0
(-300 1750);
DISPLAY 1.021277 (-300 1750);
DISPLAY INVISIBLE (-300 1750);
FORCEADD OFFPAGE..4
R 2
(-50 1850);
FORCEPROP 2 LAST $XR0 167 
J 0
(-302 1850);
DISPLAY 0.638298 (-302 1850);
PAINT MONO (-302 1850);
FORCEPROP 2 LAST CDS_LIB standard
J 0
(-50 1850);
DISPLAY INVISIBLE (-50 1850);
FORCEPROP 1 LAST OFFPAGE TRUE
J 2
(-375 1725);
DISPLAY 0.872340 (-375 1725);
PAINT GREEN (-375 1725);
DISPLAY INVISIBLE (-375 1725);
FORCEPROP 1 LAST COMMENT_BODY TRUE
J 2
(-25 1750);
DISPLAY 0.872340 (-25 1750);
PAINT GREEN (-25 1750);
DISPLAY INVISIBLE (-25 1750);
FORCEPROP 2 LAST PATH I91
J 0
(-300 1900);
DISPLAY 1.021277 (-300 1900);
DISPLAY INVISIBLE (-300 1900);
FORCEADD OFFPAGE..4
R 2
(-50 1750);
FORCEPROP 2 LAST $XR0 167 
J 0
(-302 1750);
DISPLAY 0.638298 (-302 1750);
PAINT MONO (-302 1750);
FORCEPROP 1 LAST COMMENT_BODY TRUE
J 2
(-25 1650);
DISPLAY 0.872340 (-25 1650);
PAINT GREEN (-25 1650);
DISPLAY INVISIBLE (-25 1650);
FORCEPROP 1 LAST OFFPAGE TRUE
J 2
(-375 1625);
DISPLAY 0.872340 (-375 1625);
PAINT GREEN (-375 1625);
DISPLAY INVISIBLE (-375 1625);
FORCEPROP 2 LAST CDS_LIB standard
J 0
(-50 1750);
DISPLAY INVISIBLE (-50 1750);
FORCEPROP 2 LAST PATH I92
J 0
(-300 1800);
DISPLAY 1.021277 (-300 1800);
DISPLAY INVISIBLE (-300 1800);
FORCEADD OFFPAGE..4
R 2
(-50 1800);
FORCEPROP 2 LAST $XR0 167 
J 0
(-302 1800);
DISPLAY 0.638298 (-302 1800);
PAINT MONO (-302 1800);
FORCEPROP 2 LAST CDS_LIB standard
J 0
(-50 1800);
DISPLAY INVISIBLE (-50 1800);
FORCEPROP 1 LAST OFFPAGE TRUE
J 2
(-375 1675);
DISPLAY 0.872340 (-375 1675);
PAINT GREEN (-375 1675);
DISPLAY INVISIBLE (-375 1675);
FORCEPROP 1 LAST COMMENT_BODY TRUE
J 2
(-25 1700);
DISPLAY 0.872340 (-25 1700);
PAINT GREEN (-25 1700);
DISPLAY INVISIBLE (-25 1700);
FORCEPROP 2 LAST PATH I93
J 0
(-300 1850);
DISPLAY 1.021277 (-300 1850);
DISPLAY INVISIBLE (-300 1850);
FORCEADD UNIVERSAL_GND..1
(0 1875);
FORCEPROP 3 LASTPIN (0 1925) SIG_NAME GND\g
J 0
(10 1935);
DISPLAY 0.659574 (10 1935);
PAINT MONO (10 1935);
DISPLAY INVISIBLE (10 1935);
FORCEPROP 2 LAST CDS_LIB logical_power
J 0
(0 1875);
DISPLAY INVISIBLE (0 1875);
FORCEPROP 1 LAST HDL_POWER GND
J 1
(25 1800);
DISPLAY 0.872340 (25 1800);
PAINT GREEN (25 1800);
DISPLAY INVISIBLE (25 1800);
FORCEPROP 1 LAST PATH I94
J 0
(75 1875);
DISPLAY 0.872340 (75 1875);
PAINT AQUA (75 1875);
DISPLAY INVISIBLE (75 1875);
FORCEADD DS125BR111RTWR..1
(1725 1550);
FORCEPROP 1 LAST PART_NUMBER AL000125003
J 0
(1355 2396);
DISPLAY 0.723404 (1355 2396);
PAINT GREEN (1355 2396);
DISPLAY INVISIBLE (1355 2396);
FORCEPROP 2 LAST VALUE DS125BR111RTWR
J 0
(1375 2600);
DISPLAY 1.021277 (1375 2600);
FORCEPROP 2 LAST PART_TYPE SMLF
J 0
(1375 2650);
DISPLAY 1.021277 (1375 2650);
FORCEPROP 2 LAST ROOM PCIE REDRIVER1_BOM2
J 0
(1375 2700);
DISPLAY 1.021277 (1375 2700);
FORCEPROP 1 LAST MATERIAL EMPTY
J 0
(1355 2269);
DISPLAY 0.723404 (1355 2269);
PAINT GREEN (1355 2269);
FORCEPROP 1 LAST $LOCATION U328
J 0
(1355 2543);
DISPLAY 0.723404 (1355 2543);
PAINT GREEN (1355 2543);
FORCEPROP 2 LASTPIN (1200 1400) $PN 3
J 2
(1190 1410);
DISPLAY 0.680851 (1190 1410);
PAINT MONO (1190 1410);
FORCEPROP 2 LASTPIN (1200 1850) $PN 10
J 2
(1190 1860);
DISPLAY 0.680851 (1190 1860);
PAINT MONO (1190 1860);
FORCEPROP 2 LASTPIN (1200 1800) $PN 9
J 2
(1190 1810);
DISPLAY 0.680851 (1190 1810);
PAINT MONO (1190 1810);
FORCEPROP 2 LASTPIN (1200 1700) $PN 1
J 2
(1190 1710);
DISPLAY 0.680851 (1190 1710);
PAINT MONO (1190 1710);
FORCEPROP 2 LASTPIN (1200 1750) $PN 2
J 2
(1190 1760);
DISPLAY 0.680851 (1190 1760);
PAINT MONO (1190 1760);
FORCEPROP 2 LASTPIN (1200 1200) $PN 24
J 2
(1190 1210);
DISPLAY 0.680851 (1190 1210);
PAINT MONO (1190 1210);
FORCEPROP 2 LASTPIN (1200 1150) $PN 23
J 2
(1190 1160);
DISPLAY 0.680851 (1190 1160);
PAINT MONO (1190 1160);
FORCEPROP 2 LASTPIN (1200 1050) $PN 11
J 2
(1190 1060);
DISPLAY 0.680851 (1190 1060);
PAINT MONO (1190 1060);
FORCEPROP 2 LASTPIN (1200 1000) $PN 12
J 2
(1190 1010);
DISPLAY 0.680851 (1190 1010);
PAINT MONO (1190 1010);
FORCEPROP 2 LASTPIN (2250 1200) $PN 7
J 0
(2260 1210);
DISPLAY 0.680851 (2260 1210);
PAINT MONO (2260 1210);
FORCEPROP 2 LASTPIN (2250 1150) $PN 8
J 0
(2260 1160);
DISPLAY 0.680851 (2260 1160);
PAINT MONO (2260 1160);
FORCEPROP 2 LASTPIN (2250 1050) $PN 20
J 0
(2260 1060);
DISPLAY 0.680851 (2260 1060);
PAINT MONO (2260 1060);
FORCEPROP 2 LASTPIN (2250 1000) $PN 19
J 0
(2260 1010);
DISPLAY 0.680851 (2260 1010);
PAINT MONO (2260 1010);
FORCEPROP 2 LASTPIN (2250 1450) $PN 6
J 0
(2260 1460);
DISPLAY 0.680851 (2260 1460);
PAINT MONO (2260 1460);
FORCEPROP 2 LASTPIN (2250 2050) $PN 13
J 0
(2260 2060);
DISPLAY 0.680851 (2260 2060);
PAINT MONO (2260 2060);
FORCEPROP 2 LASTPIN (2250 1600) $PN 18
J 0
(2260 1610);
DISPLAY 0.680851 (2260 1610);
PAINT MONO (2260 1610);
FORCEPROP 2 LASTPIN (1200 1300) $PN 5
J 2
(1190 1310);
DISPLAY 0.680851 (1190 1310);
PAINT MONO (1190 1310);
FORCEPROP 2 LASTPIN (2250 1900) $PN 14
J 0
(2260 1910);
DISPLAY 0.680851 (2260 1910);
PAINT MONO (2260 1910);
FORCEPROP 2 LASTPIN (1200 1350) $PN 4
J 2
(1190 1360);
DISPLAY 0.680851 (1190 1360);
PAINT MONO (1190 1360);
FORCEPROP 2 LASTPIN (2250 900) $PN 25
J 0
(2260 910);
DISPLAY 0.680851 (2260 910);
PAINT MONO (2260 910);
FORCEPROP 2 LASTPIN (1200 2100) $PN 21
J 2
(1190 2110);
DISPLAY 0.680851 (1190 2110);
PAINT MONO (1190 2110);
FORCEPROP 2 LASTPIN (1200 2050) $PN 22
J 2
(1190 2060);
DISPLAY 0.680851 (1190 2060);
PAINT MONO (1190 2060);
FORCEPROP 2 LASTPIN (1200 1950) $PN 16
J 2
(1190 1960);
DISPLAY 0.680851 (1190 1960);
PAINT MONO (1190 1960);
FORCEPROP 2 LASTPIN (1200 2150) $PN 15
J 2
(1190 2160);
DISPLAY 0.680851 (1190 2160);
PAINT MONO (1190 2160);
FORCEPROP 2 LASTPIN (2250 2200) $PN 17
J 0
(2260 2210);
DISPLAY 0.680851 (2260 2210);
PAINT MONO (2260 2210);
FORCEPROP 1 LAST PATH I95
J 0
(1725 1550);
DISPLAY 0.723404 (1725 1550);
PAINT GREEN (1725 1550);
DISPLAY INVISIBLE (1725 1550);
FORCEPROP 2 LAST SEC_TYPE 
J 0
(1375 2700);
DISPLAY 1.021277 (1375 2700);
DISPLAY INVISIBLE (1375 2700);
FORCEPROP 1 LAST NEEDS_NO_SIZE TRUE
J 0
(1725 1550);
DISPLAY 0.723404 (1725 1550);
PAINT GREEN (1725 1550);
DISPLAY INVISIBLE (1725 1550);
FORCEPROP 1 LAST CDS_LMAN_SYM_OUTLINE -375,700,375,-700
J 0
(1725 1550);
DISPLAY 0.468085 (1725 1550);
PAINT GREEN (1725 1550);
DISPLAY INVISIBLE (1725 1550);
FORCEPROP 2 LAST CDS_LIB pure_quanta
J 0
(1725 1550);
DISPLAY INVISIBLE (1725 1550);
FORCEPROP 0 LAST CDS_LOCATION U328
J 0
(1375 2700);
DISPLAY 1.021277 (1375 2700);
DISPLAY INVISIBLE (1375 2700);
FORCEPROP 2 LAST SEC 1
J 0
(1375 2700);
DISPLAY 0.680851 (1375 2700);
PAINT MONO (1375 2700);
DISPLAY INVISIBLE (1375 2700);
FORCEADD Q_CAP..1
R 2
(0 2175);
FORCEPROP 1 LAST PART_NUMBER CH5104KEB02
J 0
(50 2075);
DISPLAY 0.510638 (50 2075);
DISPLAY INVISIBLE (50 2075);
FORCEPROP 1 LAST VALUE 1UF
J 0
(50 2275);
DISPLAY 0.510638 (50 2275);
FORCEPROP 1 LAST VOLTAGE 25V
J 0
(50 2225);
DISPLAY 0.510638 (50 2225);
FORCEPROP 1 LAST PACK_TYPE C0402
J 0
(50 2025);
DISPLAY 0.510638 (50 2025);
FORCEPROP 1 LAST TOLERANCE 10%
J 0
(50 2175);
DISPLAY 0.510638 (50 2175);
FORCEPROP 1 LAST MATERIAL X6S
J 0
(50 2125);
DISPLAY 0.510638 (50 2125);
FORCEPROP 2 LAST ROOM PCIE REDRIVER1_BOM2
J 0
(25 2425);
DISPLAY 0.510638 (25 2425);
FORCEPROP 1 LAST $LOCATION C2355
J 0
(50 2325);
DISPLAY 0.787234 (50 2325);
FORCEPROP 1 LASTPIN (0 2275) $PN 1
J 2
(-10 2255);
DISPLAY 0.787234 (-10 2255);
PAINT MONO (-10 2255);
FORCEPROP 1 LASTPIN (0 2075) $PN 2
J 2
(-10 2055);
DISPLAY 0.787234 (-10 2055);
PAINT MONO (-10 2055);
FORCEPROP 2 LAST CDS_LIB pure_quanta
J 0
(0 2175);
DISPLAY INVISIBLE (0 2175);
FORCEPROP 1 LAST PATH I96
J 2
(-50 2325);
DISPLAY 0.978723 (-50 2325);
PAINT WHITE (-50 2325);
DISPLAY INVISIBLE (-50 2325);
FORCEPROP 0 LAST CDS_LOCATION C2355
J 0
(50 2375);
DISPLAY 1.021277 (50 2375);
DISPLAY INVISIBLE (50 2375);
FORCEPROP 0 LAST $SEC 1
J 0
(50 2375);
DISPLAY 0.680851 (50 2375);
PAINT MONO (50 2375);
DISPLAY INVISIBLE (50 2375);
FORCEPROP 0 LAST CDS_SEC 1
J 0
(50 2375);
DISPLAY 1.021277 (50 2375);
DISPLAY INVISIBLE (50 2375);
FORCEADD UNIVERSAL_POWER..1
(0 2550);
FORCEPROP 3 LASTPIN (0 2500) SIG_NAME P3V3_AUX\g
J 0
(10 2510);
DISPLAY 0.659574 (10 2510);
PAINT MONO (10 2510);
DISPLAY INVISIBLE (10 2510);
FORCEPROP 1 LAST HDL_POWER P3V3_AUX
J 1
(0 2600);
DISPLAY 0.872340 (0 2600);
PAINT GREEN (0 2600);
FORCEPROP 2 LAST CDS_LIB logical_power
J 0
(0 2550);
DISPLAY INVISIBLE (0 2550);
FORCEPROP 1 LAST PATH I97
J 0
(50 2575);
DISPLAY 0.872340 (50 2575);
PAINT AQUA (50 2575);
DISPLAY INVISIBLE (50 2575);
FORCEADD Q_CAP..1
R 2
(325 2175);
FORCEPROP 1 LAST PART_NUMBER CH6103KEA00
J 0
(375 2075);
DISPLAY 0.489362 (375 2075);
DISPLAY INVISIBLE (375 2075);
FORCEPROP 1 LAST MATERIAL X6S
J 0
(375 2125);
DISPLAY 0.489362 (375 2125);
FORCEPROP 1 LAST VOLTAGE 16V
J 0
(375 2225);
DISPLAY 0.489362 (375 2225);
FORCEPROP 1 LAST TOLERANCE 10%
J 0
(375 2175);
DISPLAY 0.489362 (375 2175);
FORCEPROP 1 LAST PACK_TYPE C0805
J 0
(375 2025);
DISPLAY 0.489362 (375 2025);
FORCEPROP 1 LAST VALUE 10UF
J 0
(375 2275);
DISPLAY 0.489362 (375 2275);
FORCEPROP 2 LAST ROOM PCIE REDRIVER1_BOM2
J 0
(350 2375);
DISPLAY 0.510638 (350 2375);
FORCEPROP 1 LAST $LOCATION C2356
J 0
(375 2325);
DISPLAY 0.787234 (375 2325);
FORCEPROP 1 LASTPIN (325 2275) $PN 1
J 2
(315 2255);
DISPLAY 0.787234 (315 2255);
PAINT MONO (315 2255);
FORCEPROP 1 LASTPIN (325 2075) $PN 2
J 2
(315 2055);
DISPLAY 0.787234 (315 2055);
PAINT MONO (315 2055);
FORCEPROP 2 LAST BOM_COST VR_SYSTEM 
J 0
(275 2325);
DISPLAY 0.680851 (275 2325);
DISPLAY INVISIBLE (275 2325);
FORCEPROP 2 LAST CDS_LIB pure_quanta
J 0
(325 2175);
DISPLAY INVISIBLE (325 2175);
FORCEPROP 1 LAST PATH I98
J 2
(275 2325);
DISPLAY 0.978723 (275 2325);
PAINT WHITE (275 2325);
DISPLAY INVISIBLE (275 2325);
FORCEPROP 0 LAST CDS_LOCATION C2356
J 0
(375 2375);
DISPLAY 1.021277 (375 2375);
DISPLAY INVISIBLE (375 2375);
FORCEPROP 0 LAST $SEC 1
J 0
(375 2375);
DISPLAY 0.680851 (375 2375);
PAINT MONO (375 2375);
DISPLAY INVISIBLE (375 2375);
FORCEPROP 0 LAST CDS_SEC 1
J 0
(375 2375);
DISPLAY 1.021277 (375 2375);
DISPLAY INVISIBLE (375 2375);
FORCEADD Q_CAP..1
(625 2175);
FORCEPROP 1 LAST PART_NUMBER CH4104K1B00
J 0
(675 2025);
DISPLAY 0.808511 (675 2025);
DISPLAY INVISIBLE (675 2025);
FORCEPROP 1 LAST PACK_TYPE 0402
J 0
(675 2025);
DISPLAY 0.638298 (675 2025);
FORCEPROP 1 LAST TOLERANCE 10%
J 0
(675 2125);
DISPLAY 0.638298 (675 2125);
FORCEPROP 1 LAST MATERIAL X7R
J 0
(675 2075);
DISPLAY 0.638298 (675 2075);
FORCEPROP 1 LAST VALUE 0.1UF
J 0
(675 2225);
DISPLAY 0.638298 (675 2225);
FORCEPROP 1 LAST VOLTAGE 25V
J 0
(675 2175);
DISPLAY 0.638298 (675 2175);
FORCEPROP 2 LAST ROOM PCIE REDRIVER1_BOM2
J 0
(675 2325);
DISPLAY 0.510638 (675 2325);
FORCEPROP 1 LAST $LOCATION C2357
J 0
(675 2275);
DISPLAY 0.787234 (675 2275);
FORCEPROP 1 LASTPIN (625 2275) $PN 1
J 0
(635 2255);
DISPLAY 0.787234 (635 2255);
PAINT MONO (635 2255);
FORCEPROP 1 LASTPIN (625 2075) $PN 2
J 0
(635 2055);
DISPLAY 0.787234 (635 2055);
PAINT MONO (635 2055);
FORCEPROP 2 LAST CDS_LIB pure_quanta
J 0
(625 2175);
DISPLAY INVISIBLE (625 2175);
FORCEPROP 1 LAST PATH I99
J 0
(675 2325);
DISPLAY 0.978723 (675 2325);
PAINT WHITE (675 2325);
DISPLAY INVISIBLE (675 2325);
FORCEPROP 0 LAST CDS_LOCATION C2357
J 0
(675 2325);
DISPLAY 1.021277 (675 2325);
DISPLAY INVISIBLE (675 2325);
FORCEPROP 0 LAST $SEC 1
J 0
(675 2325);
DISPLAY 0.680851 (675 2325);
PAINT MONO (675 2325);
DISPLAY INVISIBLE (675 2325);
FORCEPROP 0 LAST CDS_SEC 1
J 0
(675 2325);
DISPLAY 1.021277 (675 2325);
DISPLAY INVISIBLE (675 2325);
FORCEADD QUANTA_TITLE_BLOCK_C..1
(4675 -3325);
FORCEPROP 0 LAST CDS_CON_LAST_MODIFIED Fri Aug 25 14:02:38 2023
J 0
(2790 -3310);
PAINT MONO (2790 -3310);
DISPLAY INVISIBLE (2790 -3310);
FORCEPROP 2 LAST CUSTOM_TXT_CDS <XR_PAGE_TITLE>
J 0
(-3215 1925);
DISPLAY 0.638298 (-3215 1925);
PAINT PINK (-3215 1925);
DISPLAY INVISIBLE (-3215 1925);
FORCEPROP 2 LAST CUSTOM_TXT_CDS <CON_LAST_MODIFIED>
J 0
(2790 -3310);
DISPLAY 0.978723 (2790 -3310);
FORCEPROP 2 LAST CUSTOM_TXT_CDS <Q_REV>
J 0
(4491 -3222);
DISPLAY 1.212766 (4491 -3222);
FORCEPROP 2 LAST CUSTOM_TXT_CDS <CON_PAGE_NUM> OF <CON_TOTAL_PAGES>
J 0
(4229 -3307);
DISPLAY 0.978723 (4229 -3307);
FORCEPROP 2 LAST CUSTOM_TXT_CDS <Q_NUMBER>
J 0
(3272 -3222);
DISPLAY 1.212766 (3272 -3222);
FORCEPROP 2 LAST CUSTOM_TXT_CDS <Q_PROJ>
J 0
(2293 -3223);
DISPLAY 1.212766 (2293 -3223);
FORCEPROP 2 LAST CUSTOM_TXT_CDS <NAME_1>
J 0
(1500 -3150);
FORCEPROP 2 LAST CUSTOM_TXT_CDS <NAME_2>
J 0
(1500 -3275);
FORCEPROP 1 LAST Q_TITLE FPGA- PCIE - RE-DRIVER(CO-LAYOUT)
J 0
(-4575 -3275);
DISPLAY 2.446809 (-4575 -3275);
PAINT GREEN (-4575 -3275);
FORCEPROP 1 LAST Q_DEPT 
J 1
(912 -3276);
DISPLAY 1.957447 (912 -3276);
PAINT GREEN (912 -3276);
FORCEPROP 2 LAST CDS_XR_PAGE_TITLE CR-167 : @S9S_MB_2U_LIB.S9S_MB_2U(SCH_1):PAGE167
J 0
(-3215 1925);
DISPLAY 0.638298 (-3215 1925);
PAINT PINK (-3215 1925);
DISPLAY INVISIBLE (-3215 1925);
FORCEPROP 1 LAST COMMENT_BODY TRUE
J 0
(4687 -3338);
DISPLAY 0.978723 (4687 -3338);
PAINT GREEN (4687 -3338);
DISPLAY INVISIBLE (4687 -3338);
FORCEPROP 2 LAST CDS_LIB pure_quanta
J 0
(4675 -3325);
PAINT MONO (4675 -3325);
DISPLAY INVISIBLE (4675 -3325);
FORCEPROP 1 LAST CDS_LMAN_SYM_OUTLINE -9475,6775,100,-125
J 0
(4675 -3325);
DISPLAY 0.468085 (4675 -3325);
PAINT GREEN (4675 -3325);
DISPLAY INVISIBLE (4675 -3325);
FORCEPROP 2 LAST PAGE_BORDER TRUE
J 0
(-3215 1925);
DISPLAY 0.638298 (-3215 1925);
PAINT PINK (-3215 1925);
DISPLAY INVISIBLE (-3215 1925);
FORCEADD DNS..2
(1725 1475);
PAINT RED (1725 1475);
FORCEPROP 1 LAST COMMENT_BODY TRUE
R 1
J 0
(1800 1250);
DISPLAY 0.872340 (1800 1250);
PAINT GREEN (1800 1250);
DISPLAY INVISIBLE (1800 1250);
FORCEPROP 2 LAST CDS_LIB mstr_misc
J 0
(1725 1475);
DISPLAY INVISIBLE (1725 1475);
FORCEADD DNS..2
(-2800 0);
PAINT RED (-2800 0);
FORCEPROP 2 LAST CDS_LIB mstr_misc
J 0
(-2800 0);
DISPLAY INVISIBLE (-2800 0);
FORCEPROP 1 LAST COMMENT_BODY TRUE
R 1
J 0
(-2725 -225);
DISPLAY 0.872340 (-2725 -225);
PAINT GREEN (-2725 -225);
DISPLAY INVISIBLE (-2725 -225);
FORCEADD DNS..2
(-2825 625);
PAINT RED (-2825 625);
FORCEPROP 1 LAST COMMENT_BODY TRUE
R 1
J 0
(-2750 400);
DISPLAY 0.872340 (-2750 400);
PAINT GREEN (-2750 400);
DISPLAY INVISIBLE (-2750 400);
FORCEPROP 2 LAST CDS_LIB mstr_misc
J 0
(-2825 625);
DISPLAY INVISIBLE (-2825 625);
FORCEADD DNS..2
(-1550 -1950);
PAINT RED (-1550 -1950);
FORCEPROP 2 LAST CDS_LIB mstr_misc
J 0
(-1550 -1950);
DISPLAY INVISIBLE (-1550 -1950);
FORCEPROP 1 LAST COMMENT_BODY TRUE
R 1
J 0
(-1475 -2175);
DISPLAY 0.872340 (-1475 -2175);
PAINT GREEN (-1475 -2175);
DISPLAY INVISIBLE (-1475 -2175);
FORCEADD DNS..2
(-1125 -1950);
PAINT RED (-1125 -1950);
FORCEPROP 1 LAST COMMENT_BODY TRUE
R 1
J 0
(-1050 -2175);
DISPLAY 0.872340 (-1050 -2175);
PAINT GREEN (-1050 -2175);
DISPLAY INVISIBLE (-1050 -2175);
FORCEPROP 2 LAST CDS_LIB mstr_misc
J 0
(-1125 -1950);
DISPLAY INVISIBLE (-1125 -1950);
FORCEADD DNS..2
(-1125 -1025);
PAINT RED (-1125 -1025);
FORCEPROP 2 LAST CDS_LIB mstr_misc
J 0
(-1125 -1025);
DISPLAY INVISIBLE (-1125 -1025);
FORCEPROP 1 LAST COMMENT_BODY TRUE
R 1
J 0
(-1050 -1250);
DISPLAY 0.872340 (-1050 -1250);
PAINT GREEN (-1050 -1250);
DISPLAY INVISIBLE (-1050 -1250);
FORCEADD DNS..2
(-1125 -475);
PAINT RED (-1125 -475);
FORCEPROP 2 LAST CDS_LIB mstr_misc
J 0
(-1125 -475);
DISPLAY INVISIBLE (-1125 -475);
FORCEPROP 1 LAST COMMENT_BODY TRUE
R 1
J 0
(-1050 -700);
DISPLAY 0.872340 (-1050 -700);
PAINT GREEN (-1050 -700);
DISPLAY INVISIBLE (-1050 -700);
FORCEADD DNS..2
(375 -2675);
PAINT RED (375 -2675);
FORCEPROP 2 LAST CDS_LIB mstr_misc
J 0
(375 -2675);
DISPLAY INVISIBLE (375 -2675);
FORCEPROP 1 LAST COMMENT_BODY TRUE
R 1
J 0
(450 -2900);
DISPLAY 0.872340 (450 -2900);
PAINT GREEN (450 -2900);
DISPLAY INVISIBLE (450 -2900);
FORCEADD DNS..2
(375 -2150);
PAINT RED (375 -2150);
FORCEPROP 1 LAST COMMENT_BODY TRUE
R 1
J 0
(450 -2375);
DISPLAY 0.872340 (450 -2375);
PAINT GREEN (450 -2375);
DISPLAY INVISIBLE (450 -2375);
FORCEPROP 2 LAST CDS_LIB mstr_misc
J 0
(375 -2150);
DISPLAY INVISIBLE (375 -2150);
FORCEADD DNS..2
(1575 -2700);
PAINT RED (1575 -2700);
FORCEPROP 1 LAST COMMENT_BODY TRUE
R 1
J 0
(1650 -2925);
DISPLAY 0.872340 (1650 -2925);
PAINT GREEN (1650 -2925);
DISPLAY INVISIBLE (1650 -2925);
FORCEPROP 2 LAST CDS_LIB mstr_misc
J 0
(1575 -2700);
DISPLAY INVISIBLE (1575 -2700);
FORCEADD DNS..2
(400 -1050);
PAINT RED (400 -1050);
FORCEPROP 2 LAST CDS_LIB mstr_misc
J 0
(400 -1050);
DISPLAY INVISIBLE (400 -1050);
FORCEPROP 1 LAST COMMENT_BODY TRUE
R 1
J 0
(475 -1275);
DISPLAY 0.872340 (475 -1275);
PAINT GREEN (475 -1275);
DISPLAY INVISIBLE (475 -1275);
FORCEADD DNS..2
(-50 -500);
PAINT RED (-50 -500);
FORCEPROP 1 LAST COMMENT_BODY TRUE
R 1
J 0
(25 -725);
DISPLAY 0.872340 (25 -725);
PAINT GREEN (25 -725);
DISPLAY INVISIBLE (25 -725);
FORCEPROP 2 LAST CDS_LIB mstr_misc
J 0
(-50 -500);
DISPLAY INVISIBLE (-50 -500);
FORCEADD DNS..2
(375 -500);
PAINT RED (375 -500);
FORCEPROP 2 LAST CDS_LIB mstr_misc
J 0
(375 -500);
DISPLAY INVISIBLE (375 -500);
FORCEPROP 1 LAST COMMENT_BODY TRUE
R 1
J 0
(450 -725);
DISPLAY 0.872340 (450 -725);
PAINT GREEN (450 -725);
DISPLAY INVISIBLE (450 -725);
FORCEADD DNS..2
(2750 -2675);
PAINT RED (2750 -2675);
FORCEPROP 1 LAST COMMENT_BODY TRUE
R 1
J 0
(2825 -2900);
DISPLAY 0.872340 (2825 -2900);
PAINT GREEN (2825 -2900);
DISPLAY INVISIBLE (2825 -2900);
FORCEPROP 2 LAST CDS_LIB mstr_misc
J 0
(2750 -2675);
DISPLAY INVISIBLE (2750 -2675);
FORCEADD DNS..2
(-1550 -475);
PAINT RED (-1550 -475);
FORCEPROP 1 LAST COMMENT_BODY TRUE
R 1
J 0
(-1475 -700);
DISPLAY 0.872340 (-1475 -700);
PAINT GREEN (-1475 -700);
DISPLAY INVISIBLE (-1475 -700);
FORCEPROP 2 LAST CDS_LIB mstr_misc
J 0
(-1550 -475);
DISPLAY INVISIBLE (-1550 -475);
FORCEADD DNS..2
(-2700 1900);
PAINT RED (-2700 1900);
FORCEPROP 2 LAST CDS_LIB mstr_misc
J 0
(-2700 1900);
DISPLAY INVISIBLE (-2700 1900);
FORCEPROP 1 LAST COMMENT_BODY TRUE
R 1
J 0
(-2625 1675);
DISPLAY 0.872340 (-2625 1675);
PAINT GREEN (-2625 1675);
DISPLAY INVISIBLE (-2625 1675);
FORCEADD DNS..2
(-2700 2525);
PAINT RED (-2700 2525);
FORCEPROP 2 LAST CDS_LIB mstr_misc
J 0
(-2700 2525);
DISPLAY INVISIBLE (-2700 2525);
FORCEPROP 1 LAST COMMENT_BODY TRUE
R 1
J 0
(-2625 2300);
DISPLAY 0.872340 (-2625 2300);
PAINT GREEN (-2625 2300);
DISPLAY INVISIBLE (-2625 2300);
WIRE 16 -1 (1575 -2050)(1575 -1900);
WIRE 16 -1 (-1550 -200)(-1550 -250);
WIRE 16 -1 (2750 -2025)(2750 -1875);
WIRE 16 -1 (-50 -225)(-50 -275);
WIRE 16 -1 (-1550 -1675)(-1550 -1725);
WIRE 16 -1 (0 2475)(0 2500);
WIRE 16 -1 (0 2475)(325 2475);
WIRE 16 -1 (0 2275)(0 2475);
WIRE 16 -1 (375 -2025)(375 -1875);
WIRE 16 -1 (-1550 -2750)(-1550 -2575);
WIRE 16 -1 (-1125 -2750)(-1125 -2575);
WIRE 16 -1 (-1550 -1275)(-1550 -1100);
WIRE 16 -1 (-1125 -1275)(-1125 -1100);
WIRE 16 -1 (-825 1050)(-825 900);
WIRE 16 -1 (375 -2825)(375 -2750);
WIRE 16 -1 (1575 -2850)(1575 -2775);
WIRE 16 -1 (-50 -1300)(-50 -1125);
WIRE 16 -1 (375 -1300)(375 -1125);
WIRE 16 -1 (2750 -2825)(2750 -2750);
WIRE 16 -1 (0 1925)(0 1950);
WIRE 16 -1 (2375 825)(2375 900);
WIRE 16 -1 (-1125 -900)(-1125 -725);
WIRE 16 -1 (-1125 -725)(-525 -725);
FORCEPROP 2 LAST SIG_NAME FM_P2E_BUF2_EQB0
J 0
(-1085 -715);
DISPLAY 0.638298 (-1085 -715);
PAINT WHITE (-1085 -715);
WIRE 16 -1 (-1125 -550)(-1125 -725);
WIRE 16 -1 (325 2475)(325 2275);
WIRE 16 -1 (1125 2475)(325 2475);
WIRE 16 -1 (1125 2150)(1125 2475);
WIRE 16 -1 (1200 2150)(1125 2150);
WIRE 16 -1 (625 2400)(625 2275);
WIRE 16 -1 (850 2400)(625 2400);
WIRE 16 -1 (850 2275)(850 2400);
WIRE 16 -1 (1050 2050)(1200 2050);
WIRE 16 -1 (1050 2100)(1050 2050);
WIRE 16 -1 (1200 2100)(1050 2100);
WIRE 16 -1 (1050 2400)(850 2400);
FORCEPROP 2 LAST SIG_NAME P2E_BUF2_VDD
J 0
(690 2410);
DISPLAY 0.510638 (690 2410);
PAINT WHITE (690 2410);
WIRE 16 -1 (1050 2400)(1050 2100);
WIRE 16 -1 (0 2075)(0 1950);
WIRE 16 -1 (0 1950)(325 1950);
WIRE 16 -1 (325 1950)(325 2075);
WIRE 16 -1 (625 1950)(325 1950);
WIRE 16 -1 (625 2075)(625 1950);
WIRE 16 -1 (625 1950)(850 1950);
WIRE 16 -1 (850 1950)(850 2075);
WIRE 16 -1 (1200 1950)(850 1950);
WIRE 16 -1 (1200 1850)(0 1850);
FORCEPROP 2 LAST SIG_NAME FM_P2E_BUF2_EQA0
J 0
(265 1860);
DISPLAY 0.553191 (265 1860);
PAINT WHITE (265 1860);
WIRE 16 -1 (1200 1800)(0 1800);
FORCEPROP 2 LAST SIG_NAME FM_P2E_BUF2_EQA1
J 0
(265 1810);
DISPLAY 0.553191 (265 1810);
PAINT WHITE (265 1810);
WIRE 16 -1 (1200 1750)(0 1750);
FORCEPROP 2 LAST SIG_NAME FM_P2E_BUF2_EQB1
J 0
(265 1760);
DISPLAY 0.553191 (265 1760);
PAINT WHITE (265 1760);
WIRE 16 -1 (1200 1700)(0 1700);
FORCEPROP 2 LAST SIG_NAME FM_P2E_BUF2_EQB0
J 0
(265 1710);
DISPLAY 0.553191 (265 1710);
PAINT WHITE (265 1710);
WIRE 16 -1 (-825 1400)(-825 1250);
WIRE 16 -1 (-825 1400)(1200 1400);
FORCEPROP 2 LAST SIG_NAME PD_P2E_BUF2_ENSMB
J 0
(265 1410);
DISPLAY 0.553191 (265 1410);
PAINT WHITE (265 1410);
WIRE 16 -1 (1200 1350)(0 1350);
FORCEPROP 2 LAST SIG_NAME FM_P2E_BUF2_VODA_DB
J 0
(265 1360);
DISPLAY 0.553191 (265 1360);
PAINT WHITE (265 1360);
WIRE 16 -1 (1200 1300)(0 1300);
FORCEPROP 2 LAST SIG_NAME FM_P2E_BUF2_VODB_DB
J 0
(265 1310);
DISPLAY 0.553191 (265 1310);
PAINT WHITE (265 1310);
WIRE 16 -1 (1200 1200)(0 1200);
FORCEPROP 2 LAST SIG_NAME P2E_MB_BMC_TX_C_R2_DP<0>
J 0
(265 1210);
DISPLAY 0.553191 (265 1210);
PAINT WHITE (265 1210);
WIRE 16 -1 (1200 1150)(0 1150);
FORCEPROP 2 LAST SIG_NAME P2E_MB_BMC_TX_C_R2_DN<0>
J 0
(265 1160);
DISPLAY 0.553191 (265 1160);
PAINT WHITE (265 1160);
WIRE 16 -1 (1200 1050)(-25 1050);
FORCEPROP 2 LAST SIG_NAME P2E_MB_BMC_RX_R2_DP<0>
J 0
(249 1060);
DISPLAY 0.553191 (249 1060);
PAINT WHITE (249 1060);
WIRE 16 -1 (1200 1000)(-25 1000);
FORCEPROP 2 LAST SIG_NAME P2E_MB_BMC_RX_R2_DN<0>
J 0
(249 1010);
DISPLAY 0.553191 (249 1010);
PAINT WHITE (249 1010);
WIRE 16 -1 (-50 -925)(-50 -700);
WIRE 16 -1 (-50 -700)(-50 -575);
WIRE 16 -1 (-50 -700)(975 -700);
FORCEPROP 2 LAST SIG_NAME FM_P2E_BUF2_EQA1
J 0
(415 -690);
DISPLAY 0.638298 (415 -690);
PAINT WHITE (415 -690);
WIRE 16 -1 (375 -925)(375 -750);
WIRE 16 -1 (375 -750)(975 -750);
FORCEPROP 2 LAST SIG_NAME FM_P2E_BUF2_EQA0
J 0
(415 -740);
DISPLAY 0.638298 (415 -740);
PAINT WHITE (415 -740);
WIRE 16 -1 (375 -575)(375 -750);
WIRE 16 -1 (-1550 -900)(-1550 -675);
WIRE 16 -1 (-1550 -675)(-1550 -550);
WIRE 16 -1 (-1550 -675)(-525 -675);
FORCEPROP 2 LAST SIG_NAME FM_P2E_BUF2_EQB1
J 0
(-1085 -665);
DISPLAY 0.638298 (-1085 -665);
PAINT WHITE (-1085 -665);
WIRE 16 -1 (-1550 -2375)(-1550 -2150);
WIRE 16 -1 (-1550 -2150)(-525 -2150);
FORCEPROP 2 LAST SIG_NAME FM_P2E_BUF2_VODB_DB
J 0
(-1085 -2140);
DISPLAY 0.638298 (-1085 -2140);
PAINT WHITE (-1085 -2140);
WIRE 16 -1 (-1550 -2150)(-1550 -2025);
WIRE 16 -1 (-1125 -2375)(-1125 -2200);
WIRE 16 -1 (-1125 -2200)(-525 -2200);
FORCEPROP 2 LAST SIG_NAME FM_P2E_BUF2_VODA_DB
J 0
(-1085 -2190);
DISPLAY 0.638298 (-1085 -2190);
PAINT WHITE (-1085 -2190);
WIRE 16 -1 (-1125 -2025)(-1125 -2200);
WIRE 16 -1 (-2725 600)(-2550 600);
WIRE 16 -1 (-2550 825)(-2725 825);
WIRE 16 -1 (-2550 600)(-2550 825);
WIRE 16 -1 (-1800 825)(-2550 825);
FORCEPROP 2 LAST SIG_NAME P2E_MB_BMC_TX_BUF_C_DN<0>
J 0
(-2535 835);
DISPLAY 0.553191 (-2535 835);
PAINT WHITE (-2535 835);
WIRE 16 -1 (-2725 650)(-2600 650);
WIRE 16 -1 (-2600 650)(-2600 875);
WIRE 16 -1 (-2600 875)(-2725 875);
WIRE 16 -1 (-1800 875)(-2600 875);
FORCEPROP 2 LAST SIG_NAME P2E_MB_BMC_TX_BUF_C_DP<0>
J 0
(-2535 885);
DISPLAY 0.553191 (-2535 885);
PAINT WHITE (-2535 885);
WIRE 16 -1 (-2625 1875)(-1500 1875);
FORCEPROP 2 LAST SIG_NAME P2E_MB_BMC_RX_R2_DN<0>
J 0
(-2235 1885);
DISPLAY 0.553191 (-2235 1885);
PAINT WHITE (-2235 1885);
WIRE 16 -1 (-1500 2200)(-2625 2200);
FORCEPROP 2 LAST SIG_NAME P2E_MB_BMC_RX_R1_DP<0>
J 0
(-2235 2210);
DISPLAY 0.553191 (-2235 2210);
PAINT WHITE (-2235 2210);
WIRE 16 -1 (-2625 2150)(-1500 2150);
FORCEPROP 2 LAST SIG_NAME P2E_MB_BMC_RX_R1_DN<0>
J 0
(-2235 2160);
DISPLAY 0.553191 (-2235 2160);
PAINT WHITE (-2235 2160);
WIRE 16 -1 (-1500 1925)(-2625 1925);
FORCEPROP 2 LAST SIG_NAME P2E_MB_BMC_RX_R2_DP<0>
J 0
(-2235 1935);
DISPLAY 0.553191 (-2235 1935);
PAINT WHITE (-2235 1935);
WIRE 16 2175 (-2950 550)(-2675 550);
WIRE 16 2175 (-2675 950)(-2675 550);
WIRE 16 2175 (-2950 950)(-2950 550);
WIRE 16 2175 (-2950 950)(-2675 950);
WIRE 16 -1 (-2925 825)(-3900 825);
FORCEPROP 2 LAST SIG_NAME P2E_MB_BMC_TX_BUF_DN<0>
J 0
(-3735 835);
DISPLAY 0.553191 (-3735 835);
PAINT WHITE (-3735 835);
WIRE 16 -1 (-1550 -1725)(-1550 -1825);
WIRE 16 -1 (-1125 -1725)(-1550 -1725);
WIRE 16 -1 (-1125 -1825)(-1125 -1725);
WIRE 16 -1 (-50 -275)(-50 -375);
WIRE 16 -1 (375 -275)(-50 -275);
WIRE 16 -1 (375 -375)(375 -275);
WIRE 16 -1 (-1550 -250)(-1550 -350);
WIRE 16 -1 (-1125 -250)(-1550 -250);
WIRE 16 -1 (-1125 -350)(-1125 -250);
WIRE 16 -1 (2250 900)(2375 900);
WIRE 16 -1 (2250 1600)(3125 1600);
FORCEPROP 2 LAST SIG_NAME FM_P2E_BUF2_RXDET
J 0
(2415 1610);
DISPLAY 0.680851 (2415 1610);
PAINT WHITE (2415 1610);
WIRE 16 -1 (2725 1450)(2250 1450);
FORCEPROP 2 LAST SIG_NAME FM_P2E_EN2_N
J 0
(2415 1460);
DISPLAY 0.553191 (2415 1460);
PAINT WHITE (2415 1460);
WIRE 16 -1 (2250 1900)(3125 1900);
FORCEPROP 2 LAST SIG_NAME FM_P2E_BUF2_SD_TH
J 0
(2415 1910);
DISPLAY 0.680851 (2415 1910);
PAINT WHITE (2415 1910);
WIRE 16 -1 (2700 2050)(2250 2050);
FORCEPROP 2 LAST SIG_NAME NC_RES
J 0
(2415 2060);
DISPLAY 0.702128 (2415 2060);
PAINT WHITE (2415 2060);
WIRE 16 -1 (2925 1450)(4100 1450);
FORCEPROP 2 LAST SIG_NAME CLK_GEN2_GPU_FPGA_OE_OR_N
J 0
(3315 1460);
DISPLAY 0.680851 (3315 1460);
PAINT WHITE (3315 1460);
WIRE 16 -1 (-1500 2550)(-2625 2550);
FORCEPROP 2 LAST SIG_NAME P2E_MB_BMC_TX_C_R2_DP<0>
J 0
(-2235 2560);
DISPLAY 0.553191 (-2235 2560);
PAINT WHITE (-2235 2560);
WIRE 16 -1 (-2625 2775)(-1500 2775);
FORCEPROP 2 LAST SIG_NAME P2E_MB_BMC_TX_C_R1_DN<0>
J 0
(-2235 2785);
DISPLAY 0.553191 (-2235 2785);
PAINT WHITE (-2235 2785);
WIRE 16 -1 (-1500 2825)(-2625 2825);
FORCEPROP 2 LAST SIG_NAME P2E_MB_BMC_TX_C_R1_DP<0>
J 0
(-2235 2835);
DISPLAY 0.553191 (-2235 2835);
PAINT WHITE (-2235 2835);
WIRE 16 -1 (-2625 2500)(-1500 2500);
FORCEPROP 2 LAST SIG_NAME P2E_MB_BMC_TX_C_R2_DN<0>
J 0
(-2235 2510);
DISPLAY 0.553191 (-2235 2510);
PAINT WHITE (-2235 2510);
WIRE 16 2175 (-3000 1825)(-2575 1825);
WIRE 16 2175 (-2575 2275)(-2575 1825);
WIRE 16 2175 (-3000 2275)(-3000 1825);
WIRE 16 2175 (-3000 2275)(-2575 2275);
WIRE 16 2175 (-2950 -75)(-2675 -75);
WIRE 16 2175 (-2675 325)(-2675 -75);
WIRE 16 2175 (-2950 325)(-2950 -75);
WIRE 16 2175 (-2950 325)(-2675 325);
WIRE 16 -1 (-2725 25)(-2600 25);
WIRE 16 -1 (-2600 250)(-2725 250);
WIRE 16 -1 (-2600 25)(-2600 250);
WIRE 16 -1 (-1800 250)(-2600 250);
FORCEPROP 2 LAST SIG_NAME P2E_MB_BMC_RX_BUF_DP<0>
J 0
(-2535 260);
DISPLAY 0.553191 (-2535 260);
PAINT WHITE (-2535 260);
WIRE 16 -1 (-2725 -25)(-2550 -25);
WIRE 16 -1 (-2550 -25)(-2550 200);
WIRE 16 -1 (-2550 200)(-2725 200);
WIRE 16 -1 (-1800 200)(-2550 200);
FORCEPROP 2 LAST SIG_NAME P2E_MB_BMC_RX_BUF_DN<0>
J 0
(-2535 210);
DISPLAY 0.553191 (-2535 210);
PAINT WHITE (-2535 210);
WIRE 16 -1 (-2925 200)(-3900 200);
FORCEPROP 2 LAST SIG_NAME P2E_MB_BMC_RX_BUF_C_DN<0>
J 0
(-3735 210);
DISPLAY 0.553191 (-3735 210);
PAINT WHITE (-3735 210);
WIRE 16 -1 (-2925 25)(-3900 25);
FORCEPROP 2 LAST SIG_NAME P2E_MB_BMC_RX_BUF2_C_DP<0>
J 0
(-3735 35);
DISPLAY 0.553191 (-3735 35);
PAINT WHITE (-3735 35);
WIRE 16 -1 (-2925 600)(-3900 600);
FORCEPROP 2 LAST SIG_NAME P2E_MB_BMC_TX_BUF2_DN<0>
J 0
(-3735 610);
DISPLAY 0.553191 (-3735 610);
PAINT WHITE (-3735 610);
WIRE 16 -1 (-2925 250)(-3900 250);
FORCEPROP 2 LAST SIG_NAME P2E_MB_BMC_RX_BUF_C_DP<0>
J 0
(-3735 260);
DISPLAY 0.553191 (-3735 260);
PAINT WHITE (-3735 260);
WIRE 16 -1 (-2925 650)(-3900 650);
FORCEPROP 2 LAST SIG_NAME P2E_MB_BMC_TX_BUF2_DP<0>
J 0
(-3735 660);
DISPLAY 0.553191 (-3735 660);
PAINT WHITE (-3735 660);
WIRE 16 -1 (-3250 1925)(-2825 1925);
WIRE 16 -1 (-3250 2200)(-4175 2200);
FORCEPROP 2 LAST SIG_NAME P2E_MB_BMC_RX_DP<0>
J 0
(-3910 2210);
DISPLAY 0.553191 (-3910 2210);
PAINT WHITE (-3910 2210);
WIRE 16 -1 (-3250 2200)(-3250 1925);
WIRE 16 -1 (-2825 2200)(-3250 2200);
WIRE 16 -1 (-3300 1875)(-2825 1875);
WIRE 16 -1 (-3300 2150)(-4175 2150);
FORCEPROP 2 LAST SIG_NAME P2E_MB_BMC_RX_DN<0>
J 0
(-3910 2160);
DISPLAY 0.553191 (-3910 2160);
PAINT WHITE (-3910 2160);
WIRE 16 -1 (-3300 2150)(-3300 1875);
WIRE 16 -1 (-2825 2150)(-3300 2150);
WIRE 16 -1 (-3300 2500)(-2825 2500);
WIRE 16 -1 (-3300 2775)(-4175 2775);
FORCEPROP 2 LAST SIG_NAME P2E_MB_BMC_TX_C_DN<0>
J 0
(-3910 2785);
DISPLAY 0.553191 (-3910 2785);
PAINT WHITE (-3910 2785);
WIRE 16 -1 (-3300 2775)(-3300 2500);
WIRE 16 -1 (-2825 2775)(-3300 2775);
WIRE 16 -1 (-3250 2550)(-2825 2550);
WIRE 16 -1 (-3250 2825)(-4175 2825);
FORCEPROP 2 LAST SIG_NAME P2E_MB_BMC_TX_C_DP<0>
J 0
(-3910 2835);
DISPLAY 0.553191 (-3910 2835);
PAINT WHITE (-3910 2835);
WIRE 16 -1 (-3250 2825)(-3250 2550);
WIRE 16 -1 (-2825 2825)(-3250 2825);
WIRE 16 2175 (-3000 2450)(-2575 2450);
WIRE 16 2175 (-2575 2900)(-2575 2450);
WIRE 16 2175 (-3000 2900)(-3000 2450);
WIRE 16 2175 (-3000 2900)(-2575 2900);
WIRE 16 -1 (3200 1000)(2250 1000);
FORCEPROP 2 LAST SIG_NAME P2E_MB_BMC_RX_BUF2_C_DN<0>
J 0
(2415 1010);
DISPLAY 0.553191 (2415 1010);
PAINT WHITE (2415 1010);
WIRE 16 -1 (3200 1150)(2250 1150);
FORCEPROP 2 LAST SIG_NAME P2E_MB_BMC_TX_BUF2_DN<0>
J 0
(2415 1160);
DISPLAY 0.553191 (2415 1160);
PAINT WHITE (2415 1160);
WIRE 16 -1 (1575 -2575)(1575 -2400);
WIRE 16 -1 (1575 -2400)(1575 -2250);
WIRE 16 -1 (1575 -2400)(2250 -2400);
FORCEPROP 2 LAST SIG_NAME FM_P2E_BUF2_SD_TH
J 0
(1615 -2390);
DISPLAY 0.680851 (1615 -2390);
PAINT WHITE (1615 -2390);
WIRE 16 -1 (-2925 -25)(-3900 -25);
FORCEPROP 2 LAST SIG_NAME P2E_MB_BMC_RX_BUF2_C_DN<0>
J 0
(-3735 -15);
DISPLAY 0.553191 (-3735 -15);
PAINT WHITE (-3735 -15);
WIRE 16 -1 (-2925 875)(-3900 875);
FORCEPROP 2 LAST SIG_NAME P2E_MB_BMC_TX_BUF_DP<0>
J 0
(-3735 885);
DISPLAY 0.553191 (-3735 885);
PAINT WHITE (-3735 885);
WIRE 16 -1 (375 -2550)(375 -2375);
WIRE 16 -1 (375 -2375)(375 -2225);
WIRE 16 -1 (375 -2375)(1050 -2375);
FORCEPROP 2 LAST SIG_NAME FM_P2E_BUF2_RXDET
J 0
(415 -2365);
DISPLAY 0.680851 (415 -2365);
PAINT WHITE (415 -2365);
WIRE 16 -1 (2750 -2550)(2750 -2375);
WIRE 16 -1 (2750 -2375)(2750 -2225);
WIRE 16 -1 (2750 -2375)(3425 -2375);
FORCEPROP 2 LAST SIG_NAME FM_P2E_BUF2_VOD_SEL
J 0
(2790 -2365);
DISPLAY 0.680851 (2790 -2365);
PAINT WHITE (2790 -2365);
WIRE 16 -1 (3200 1200)(2250 1200);
FORCEPROP 2 LAST SIG_NAME P2E_MB_BMC_TX_BUF2_DP<0>
J 0
(2415 1210);
DISPLAY 0.553191 (2415 1210);
PAINT WHITE (2415 1210);
WIRE 16 -1 (3200 1050)(2250 1050);
FORCEPROP 2 LAST SIG_NAME P2E_MB_BMC_RX_BUF2_C_DP<0>
J 0
(2415 1060);
DISPLAY 0.553191 (2415 1060);
PAINT WHITE (2415 1060);
WIRE 16 -1 (2250 2200)(3125 2200);
FORCEPROP 2 LAST SIG_NAME FM_P2E_BUF2_VOD_SEL
J 0
(2415 2210);
DISPLAY 0.680851 (2415 2210);
PAINT WHITE (2415 2210);
DOT 1 (850 2400);
DOT 1 (325 2475);
DOT 1 (625 1950);
DOT 1 (325 1950);
DOT 1 (0 1950);
DOT 1 (2750 -2375);
DOT 1 (375 -750);
DOT 1 (-50 -275);
DOT 1 (-50 -700);
DOT 1 (1575 -2400);
DOT 1 (375 -2375);
DOT 1 (-3250 2825);
DOT 1 (-3300 2775);
DOT 1 (-3300 2150);
DOT 1 (-3250 2200);
DOT 1 (-2550 200);
DOT 1 (-2600 250);
DOT 1 (-1550 -250);
DOT 1 (-1550 -1725);
DOT 1 (-1125 -2200);
DOT 1 (-1550 -2150);
DOT 1 (0 2475);
DOT 1 (-1125 -725);
DOT 1 (-2600 875);
DOT 1 (-2550 825);
DOT 1 (1050 2100);
DOT 1 (-1550 -675);
DOT 1 (850 1950);
FORCENOTE
FROM FPGA
(-4375 2275) 0;
DISPLAY LEFT (-4375 2275);
DISPLAY 1.063830 (-4375 2275);
PAINT YELLOW (-4375 2275);
FORCENOTE
FROM BMC
(-4375 2925) 0;
DISPLAY LEFT (-4375 2925);
DISPLAY 1.063830 (-4375 2925);
PAINT YELLOW (-4375 2925);
FORCENOTE
FROM 1ST REDRIVER
(-4100 300) 0;
DISPLAY LEFT (-4100 300);
DISPLAY 0.851064 (-4100 300);
PAINT YELLOW (-4100 300);
FORCENOTE
FROM 1ST REDRIVER
(-4100 950) 0;
DISPLAY LEFT (-4100 950);
DISPLAY 0.851064 (-4100 950);
PAINT YELLOW (-4100 950);
FORCENOTE
FROM 2ND REDRIVER
(-4100 700) 0;
DISPLAY LEFT (-4100 700);
DISPLAY 0.851064 (-4100 700);
PAINT YELLOW (-4100 700);
FORCENOTE
R4659,R4661 CO-LAY
(-3100 2975) 0;
DISPLAY LEFT (-3100 2975);
DISPLAY 0.851064 (-3100 2975);
PAINT YELLOW (-3100 2975);
FORCENOTE
R4660,R4662 CO-LAY
(-3100 2925) 0;
DISPLAY LEFT (-3100 2925);
DISPLAY 0.851064 (-3100 2925);
PAINT YELLOW (-3100 2925);
FORCENOTE
R4663,R4665 CO-LAY
(-3100 2350) 0;
DISPLAY LEFT (-3100 2350);
DISPLAY 0.851064 (-3100 2350);
PAINT YELLOW (-3100 2350);
FORCENOTE
FROM 2ND REDRIVER
(-4100 75) 0;
DISPLAY LEFT (-4100 75);
DISPLAY 0.851064 (-4100 75);
PAINT YELLOW (-4100 75);
FORCENOTE
C1869,C2354 CO-LAY
(-3150 350) 0;
DISPLAY LEFT (-3150 350);
DISPLAY 0.851064 (-3150 350);
PAINT YELLOW (-3150 350);
FORCENOTE
C1868,C2353 CO-LAY
(-3150 400) 0;
DISPLAY LEFT (-3150 400);
DISPLAY 0.851064 (-3150 400);
PAINT YELLOW (-3150 400);
FORCENOTE
R4664,R4666 CO-LAY
(-3100 2300) 0;
DISPLAY LEFT (-3100 2300);
DISPLAY 0.851064 (-3100 2300);
PAINT YELLOW (-3100 2300);
FORCENOTE
TO 1ST REDRIVER
(-1875 2925) 0;
DISPLAY LEFT (-1875 2925);
DISPLAY 0.851064 (-1875 2925);
PAINT YELLOW (-1875 2925);
FORCENOTE
TO 2ND REDRIVER
(-1875 2625) 0;
DISPLAY LEFT (-1875 2625);
DISPLAY 0.851064 (-1875 2625);
PAINT YELLOW (-1875 2625);
FORCENOTE
TO 1ST REDRIVER
(-1875 2275) 0;
DISPLAY LEFT (-1875 2275);
DISPLAY 0.851064 (-1875 2275);
PAINT YELLOW (-1875 2275);
FORCENOTE
TO 2ND REDRIVER
(-1875 1975) 0;
DISPLAY LEFT (-1875 1975);
DISPLAY 0.851064 (-1875 1975);
PAINT YELLOW (-1875 1975);
FORCENOTE
TO BMC
(-1950 325) 0;
DISPLAY LEFT (-1950 325);
DISPLAY 1.340425 (-1950 325);
PAINT YELLOW (-1950 325);
FORCENOTE
C1871,C2352 CO-LAY
(-3150 1125) 0;
DISPLAY LEFT (-3150 1125);
DISPLAY 0.851064 (-3150 1125);
PAINT YELLOW (-3150 1125);
FORCENOTE
C1870,C2351 CO-LAY
(-3150 1175) 0;
DISPLAY LEFT (-3150 1175);
DISPLAY 0.851064 (-3150 1175);
PAINT YELLOW (-3150 1175);
FORCENOTE
TO GPU FPGA
(-2225 975) 0;
DISPLAY LEFT (-2225 975);
DISPLAY 1.340425 (-2225 975);
PAINT YELLOW (-2225 975);
FORCENOTE
$CDS_IMAGE|clipboard_1_3.jpg|2642|576
(2675 -1025) 0;
DISPLAY LEFT (2675 -1025);
FORCENOTE
$CDS_IMAGE|clipboard_0_11.jpg|1477|394
(2100 -400) 0;
DISPLAY LEFT (2100 -400);
QUIT
